FILE_TYPE = MACRO_DRAWING;
SET COLOR_WIRE YELLOW;
SET COLOR_PROP ORANGE;
SET COLOR_DOT WHITE;
SET COLOR_ARC YELLOW;
SET COLOR_BODY GREEN;
SET COLOR_NOTE PURPLE;
SET PROP_DISPLAY VALUE;
SET PAGE_NUMBER P43;
FORCEADD GENOA_SP5..7
(-4700 3675);
FORCEPROP 1 LAST LOCATION U26
J 0
(-5345 6506);
DISPLAY 0.489362 (-5345 6506);
PAINT SKYBLUE (-5345 6506);
FORCEPROP 0 LAST $SEC 7
J 0
(-5325 6550);
DISPLAY 0.680851 (-5325 6550);
PAINT MONO (-5325 6550);
DISPLAY INVISIBLE (-5325 6550);
FORCEPROP 0 LAST CDS_SEC 7
J 0
(-5350 6475);
DISPLAY 1.021277 (-5350 6475);
DISPLAY INVISIBLE (-5350 6475);
FORCEPROP 0 LASTPIN (-5500 3050) $PN BC2
J 2
(-5510 3060);
DISPLAY 0.489362 (-5510 3060);
PAINT MONO (-5510 3060);
FORCEPROP 0 LASTPIN (-5500 3000) $PN BD2
J 2
(-5510 3010);
DISPLAY 0.489362 (-5510 3010);
PAINT MONO (-5510 3010);
FORCEPROP 0 LASTPIN (-5500 1900) $PN BF2
J 2
(-5510 1910);
DISPLAY 0.489362 (-5510 1910);
PAINT MONO (-5510 1910);
FORCEPROP 0 LASTPIN (-5500 1850) $PN BG2
J 2
(-5510 1860);
DISPLAY 0.489362 (-5510 1860);
PAINT MONO (-5510 1860);
FORCEPROP 0 LASTPIN (-5500 2200) $PN AR2
J 2
(-5510 2210);
DISPLAY 0.489362 (-5510 2210);
PAINT MONO (-5510 2210);
FORCEPROP 0 LASTPIN (-5500 2100) $PN AT2
J 2
(-5510 2110);
DISPLAY 0.489362 (-5510 2110);
PAINT MONO (-5510 2110);
FORCEPROP 0 LASTPIN (-5500 2900) $PN AU2
J 2
(-5510 2910);
DISPLAY 0.489362 (-5510 2910);
PAINT MONO (-5510 2910);
FORCEPROP 0 LASTPIN (-5500 2850) $PN AV4
J 2
(-5510 2860);
DISPLAY 0.489362 (-5510 2860);
PAINT MONO (-5510 2860);
FORCEPROP 0 LASTPIN (-5500 2750) $PN BN3
J 2
(-5510 2760);
DISPLAY 0.489362 (-5510 2760);
PAINT MONO (-5510 2760);
FORCEPROP 0 LASTPIN (-5500 1750) $PN AV2
J 2
(-5510 1760);
DISPLAY 0.489362 (-5510 1760);
PAINT MONO (-5510 1760);
FORCEPROP 0 LASTPIN (-5500 1700) $PN AW3
J 2
(-5510 1710);
DISPLAY 0.489362 (-5510 1710);
PAINT MONO (-5510 1710);
FORCEPROP 0 LASTPIN (-5500 1600) $PN BP4
J 2
(-5510 1610);
DISPLAY 0.489362 (-5510 1610);
PAINT MONO (-5510 1610);
FORCEPROP 0 LASTPIN (-5500 3900) $PN AW2
J 2
(-5510 3910);
DISPLAY 0.489362 (-5510 3910);
PAINT MONO (-5510 3910);
FORCEPROP 0 LASTPIN (-5500 3850) $PN AY2
J 2
(-5510 3860);
DISPLAY 0.489362 (-5510 3860);
PAINT MONO (-5510 3860);
FORCEPROP 0 LASTPIN (-5500 3800) $PN AY4
J 2
(-5510 3810);
DISPLAY 0.489362 (-5510 3810);
PAINT MONO (-5510 3810);
FORCEPROP 0 LASTPIN (-5500 3750) $PN BA3
J 2
(-5510 3760);
DISPLAY 0.489362 (-5510 3760);
PAINT MONO (-5510 3760);
FORCEPROP 0 LASTPIN (-5500 3700) $PN BA2
J 2
(-5510 3710);
DISPLAY 0.489362 (-5510 3710);
PAINT MONO (-5510 3710);
FORCEPROP 0 LASTPIN (-5500 3650) $PN BB2
J 2
(-5510 3660);
DISPLAY 0.489362 (-5510 3660);
PAINT MONO (-5510 3660);
FORCEPROP 0 LASTPIN (-5500 3600) $PN BB4
J 2
(-5510 3610);
DISPLAY 0.489362 (-5510 3610);
PAINT MONO (-5510 3610);
FORCEPROP 0 LASTPIN (-3900 2450) $PN AJ2
J 0
(-3890 2460);
DISPLAY 0.489362 (-3890 2460);
PAINT MONO (-3890 2460);
FORCEPROP 0 LASTPIN (-3900 2400) $PN AK4
J 0
(-3890 2410);
DISPLAY 0.489362 (-3890 2410);
PAINT MONO (-3890 2410);
FORCEPROP 0 LASTPIN (-3900 2350) $PN AK2
J 0
(-3890 2360);
DISPLAY 0.489362 (-3890 2360);
PAINT MONO (-3890 2360);
FORCEPROP 0 LASTPIN (-3900 2300) $PN AL3
J 0
(-3890 2310);
DISPLAY 0.489362 (-3890 2310);
PAINT MONO (-3890 2310);
FORCEPROP 0 LASTPIN (-3900 2250) $PN AN2
J 0
(-3890 2260);
DISPLAY 0.489362 (-3890 2260);
PAINT MONO (-3890 2260);
FORCEPROP 0 LASTPIN (-3900 2200) $PN AP4
J 0
(-3890 2210);
DISPLAY 0.489362 (-3890 2210);
PAINT MONO (-3890 2210);
FORCEPROP 0 LASTPIN (-3900 2150) $PN AP2
J 0
(-3890 2160);
DISPLAY 0.489362 (-3890 2160);
PAINT MONO (-3890 2160);
FORCEPROP 0 LASTPIN (-3900 2100) $PN AR3
J 0
(-3890 2110);
DISPLAY 0.489362 (-3890 2110);
PAINT MONO (-3890 2110);
FORCEPROP 0 LASTPIN (-3900 6050) $PN E2
J 0
(-3890 6060);
DISPLAY 0.489362 (-3890 6060);
PAINT MONO (-3890 6060);
FORCEPROP 0 LASTPIN (-3900 6000) $PN F4
J 0
(-3890 6010);
DISPLAY 0.489362 (-3890 6010);
PAINT MONO (-3890 6010);
FORCEPROP 0 LASTPIN (-3900 5950) $PN F2
J 0
(-3890 5960);
DISPLAY 0.489362 (-3890 5960);
PAINT MONO (-3890 5960);
FORCEPROP 0 LASTPIN (-3900 5900) $PN G3
J 0
(-3890 5910);
DISPLAY 0.489362 (-3890 5910);
PAINT MONO (-3890 5910);
FORCEPROP 0 LASTPIN (-3900 5850) $PN J2
J 0
(-3890 5860);
DISPLAY 0.489362 (-3890 5860);
PAINT MONO (-3890 5860);
FORCEPROP 0 LASTPIN (-3900 5800) $PN K4
J 0
(-3890 5810);
DISPLAY 0.489362 (-3890 5810);
PAINT MONO (-3890 5810);
FORCEPROP 0 LASTPIN (-3900 5750) $PN K2
J 0
(-3890 5760);
DISPLAY 0.489362 (-3890 5760);
PAINT MONO (-3890 5760);
FORCEPROP 0 LASTPIN (-3900 5700) $PN L3
J 0
(-3890 5710);
DISPLAY 0.489362 (-3890 5710);
PAINT MONO (-3890 5710);
FORCEPROP 0 LASTPIN (-3900 5600) $PN L2
J 0
(-3890 5610);
DISPLAY 0.489362 (-3890 5610);
PAINT MONO (-3890 5610);
FORCEPROP 0 LASTPIN (-3900 5550) $PN M4
J 0
(-3890 5560);
DISPLAY 0.489362 (-3890 5560);
PAINT MONO (-3890 5560);
FORCEPROP 0 LASTPIN (-3900 5500) $PN M2
J 0
(-3890 5510);
DISPLAY 0.489362 (-3890 5510);
PAINT MONO (-3890 5510);
FORCEPROP 0 LASTPIN (-3900 5450) $PN N3
J 0
(-3890 5460);
DISPLAY 0.489362 (-3890 5460);
PAINT MONO (-3890 5460);
FORCEPROP 0 LASTPIN (-3900 5400) $PN R2
J 0
(-3890 5410);
DISPLAY 0.489362 (-3890 5410);
PAINT MONO (-3890 5410);
FORCEPROP 0 LASTPIN (-3900 5350) $PN T4
J 0
(-3890 5360);
DISPLAY 0.489362 (-3890 5360);
PAINT MONO (-3890 5360);
FORCEPROP 0 LASTPIN (-3900 5300) $PN T2
J 0
(-3890 5310);
DISPLAY 0.489362 (-3890 5310);
PAINT MONO (-3890 5310);
FORCEPROP 0 LASTPIN (-3900 5250) $PN U3
J 0
(-3890 5260);
DISPLAY 0.489362 (-3890 5260);
PAINT MONO (-3890 5260);
FORCEPROP 0 LASTPIN (-3900 5150) $PN U2
J 0
(-3890 5160);
DISPLAY 0.489362 (-3890 5160);
PAINT MONO (-3890 5160);
FORCEPROP 0 LASTPIN (-3900 5100) $PN V4
J 0
(-3890 5110);
DISPLAY 0.489362 (-3890 5110);
PAINT MONO (-3890 5110);
FORCEPROP 0 LASTPIN (-3900 5050) $PN V2
J 0
(-3890 5060);
DISPLAY 0.489362 (-3890 5060);
PAINT MONO (-3890 5060);
FORCEPROP 0 LASTPIN (-3900 5000) $PN W3
J 0
(-3890 5010);
DISPLAY 0.489362 (-3890 5010);
PAINT MONO (-3890 5010);
FORCEPROP 0 LASTPIN (-3900 4950) $PN AA2
J 0
(-3890 4960);
DISPLAY 0.489362 (-3890 4960);
PAINT MONO (-3890 4960);
FORCEPROP 0 LASTPIN (-3900 4900) $PN AB4
J 0
(-3890 4910);
DISPLAY 0.489362 (-3890 4910);
PAINT MONO (-3890 4910);
FORCEPROP 0 LASTPIN (-3900 4850) $PN AB2
J 0
(-3890 4860);
DISPLAY 0.489362 (-3890 4860);
PAINT MONO (-3890 4860);
FORCEPROP 0 LASTPIN (-3900 4800) $PN AC3
J 0
(-3890 4810);
DISPLAY 0.489362 (-3890 4810);
PAINT MONO (-3890 4810);
FORCEPROP 0 LASTPIN (-3900 4700) $PN AC2
J 0
(-3890 4710);
DISPLAY 0.489362 (-3890 4710);
PAINT MONO (-3890 4710);
FORCEPROP 0 LASTPIN (-3900 4650) $PN AD4
J 0
(-3890 4660);
DISPLAY 0.489362 (-3890 4660);
PAINT MONO (-3890 4660);
FORCEPROP 0 LASTPIN (-3900 4600) $PN AD2
J 0
(-3890 4610);
DISPLAY 0.489362 (-3890 4610);
PAINT MONO (-3890 4610);
FORCEPROP 0 LASTPIN (-3900 4550) $PN AE3
J 0
(-3890 4560);
DISPLAY 0.489362 (-3890 4560);
PAINT MONO (-3890 4560);
FORCEPROP 0 LASTPIN (-3900 4500) $PN AG2
J 0
(-3890 4510);
DISPLAY 0.489362 (-3890 4510);
PAINT MONO (-3890 4510);
FORCEPROP 0 LASTPIN (-3900 4450) $PN AH4
J 0
(-3890 4460);
DISPLAY 0.489362 (-3890 4460);
PAINT MONO (-3890 4460);
FORCEPROP 0 LASTPIN (-3900 4400) $PN AH2
J 0
(-3890 4410);
DISPLAY 0.489362 (-3890 4410);
PAINT MONO (-3890 4410);
FORCEPROP 0 LASTPIN (-3900 4350) $PN AJ3
J 0
(-3890 4360);
DISPLAY 0.489362 (-3890 4360);
PAINT MONO (-3890 4360);
FORCEPROP 0 LASTPIN (-5500 6050) $PN G2
J 2
(-5510 6060);
DISPLAY 0.489362 (-5510 6060);
PAINT MONO (-5510 6060);
FORCEPROP 0 LASTPIN (-5500 5950) $PN N2
J 2
(-5510 5960);
DISPLAY 0.489362 (-5510 5960);
PAINT MONO (-5510 5960);
FORCEPROP 0 LASTPIN (-5500 5850) $PN W2
J 2
(-5510 5860);
DISPLAY 0.489362 (-5510 5860);
PAINT MONO (-5510 5860);
FORCEPROP 0 LASTPIN (-5500 5750) $PN AE2
J 2
(-5510 5760);
DISPLAY 0.489362 (-5510 5760);
PAINT MONO (-5510 5760);
FORCEPROP 0 LASTPIN (-5500 5650) $PN AL2
J 2
(-5510 5660);
DISPLAY 0.489362 (-5510 5660);
PAINT MONO (-5510 5660);
FORCEPROP 0 LASTPIN (-5500 5550) $PN J3
J 2
(-5510 5560);
DISPLAY 0.489362 (-5510 5560);
PAINT MONO (-5510 5560);
FORCEPROP 0 LASTPIN (-5500 5450) $PN R3
J 2
(-5510 5460);
DISPLAY 0.489362 (-5510 5460);
PAINT MONO (-5510 5460);
FORCEPROP 0 LASTPIN (-5500 5350) $PN AA3
J 2
(-5510 5360);
DISPLAY 0.489362 (-5510 5360);
PAINT MONO (-5510 5360);
FORCEPROP 0 LASTPIN (-5500 5250) $PN AG3
J 2
(-5510 5260);
DISPLAY 0.489362 (-5510 5260);
PAINT MONO (-5510 5260);
FORCEPROP 0 LASTPIN (-5500 5150) $PN AN3
J 2
(-5510 5160);
DISPLAY 0.489362 (-5510 5160);
PAINT MONO (-5510 5160);
FORCEPROP 0 LASTPIN (-5500 6000) $PN H2
J 2
(-5510 6010);
DISPLAY 0.489362 (-5510 6010);
PAINT MONO (-5510 6010);
FORCEPROP 0 LASTPIN (-5500 5900) $PN P2
J 2
(-5510 5910);
DISPLAY 0.489362 (-5510 5910);
PAINT MONO (-5510 5910);
FORCEPROP 0 LASTPIN (-5500 5800) $PN Y2
J 2
(-5510 5810);
DISPLAY 0.489362 (-5510 5810);
PAINT MONO (-5510 5810);
FORCEPROP 0 LASTPIN (-5500 5700) $PN AF2
J 2
(-5510 5710);
DISPLAY 0.489362 (-5510 5710);
PAINT MONO (-5510 5710);
FORCEPROP 0 LASTPIN (-5500 5600) $PN AM2
J 2
(-5510 5610);
DISPLAY 0.489362 (-5510 5610);
PAINT MONO (-5510 5610);
FORCEPROP 0 LASTPIN (-5500 5500) $PN H4
J 2
(-5510 5510);
DISPLAY 0.489362 (-5510 5510);
PAINT MONO (-5510 5510);
FORCEPROP 0 LASTPIN (-5500 5400) $PN P4
J 2
(-5510 5410);
DISPLAY 0.489362 (-5510 5410);
PAINT MONO (-5510 5410);
FORCEPROP 0 LASTPIN (-5500 5300) $PN Y4
J 2
(-5510 5310);
DISPLAY 0.489362 (-5510 5310);
PAINT MONO (-5510 5310);
FORCEPROP 0 LASTPIN (-5500 5200) $PN AF4
J 2
(-5510 5210);
DISPLAY 0.489362 (-5510 5210);
PAINT MONO (-5510 5210);
FORCEPROP 0 LASTPIN (-5500 5100) $PN AM4
J 2
(-5510 5110);
DISPLAY 0.489362 (-5510 5110);
PAINT MONO (-5510 5110);
FORCEPROP 0 LASTPIN (-5500 2650) $PN BC3
J 2
(-5510 2660);
DISPLAY 0.489362 (-5510 2660);
PAINT MONO (-5510 2660);
FORCEPROP 0 LASTPIN (-5500 2550) $PN BM4
J 2
(-5510 2560);
DISPLAY 0.489362 (-5510 2560);
PAINT MONO (-5510 2560);
FORCEPROP 0 LASTPIN (-5500 2500) $PN BN2
J 2
(-5510 2510);
DISPLAY 0.489362 (-5510 2510);
PAINT MONO (-5510 2510);
FORCEPROP 0 LASTPIN (-5500 2400) $PN BP2
J 2
(-5510 2410);
DISPLAY 0.489362 (-5510 2410);
PAINT MONO (-5510 2410);
FORCEPROP 0 LASTPIN (-5500 1500) $PN BL2
J 2
(-5510 1510);
DISPLAY 0.489362 (-5510 1510);
PAINT MONO (-5510 1510);
FORCEPROP 0 LASTPIN (-5500 1450) $PN BM2
J 2
(-5510 1460);
DISPLAY 0.489362 (-5510 1460);
PAINT MONO (-5510 1460);
FORCEPROP 0 LASTPIN (-5500 1350) $PN BR2
J 2
(-5510 1360);
DISPLAY 0.489362 (-5510 1360);
PAINT MONO (-5510 1360);
FORCEPROP 0 LASTPIN (-5500 3500) $PN BG3
J 2
(-5510 3510);
DISPLAY 0.489362 (-5510 3510);
PAINT MONO (-5510 3510);
FORCEPROP 0 LASTPIN (-5500 3450) $PN BH4
J 2
(-5510 3460);
DISPLAY 0.489362 (-5510 3460);
PAINT MONO (-5510 3460);
FORCEPROP 0 LASTPIN (-5500 3400) $PN BH2
J 2
(-5510 3410);
DISPLAY 0.489362 (-5510 3410);
PAINT MONO (-5510 3410);
FORCEPROP 0 LASTPIN (-5500 3350) $PN BJ2
J 2
(-5510 3360);
DISPLAY 0.489362 (-5510 3360);
PAINT MONO (-5510 3360);
FORCEPROP 0 LASTPIN (-5500 3300) $PN BJ3
J 2
(-5510 3310);
DISPLAY 0.489362 (-5510 3310);
PAINT MONO (-5510 3310);
FORCEPROP 0 LASTPIN (-5500 3250) $PN BK4
J 2
(-5510 3260);
DISPLAY 0.489362 (-5510 3260);
PAINT MONO (-5510 3260);
FORCEPROP 0 LASTPIN (-5500 3200) $PN BK2
J 2
(-5510 3210);
DISPLAY 0.489362 (-5510 3210);
PAINT MONO (-5510 3210);
FORCEPROP 0 LASTPIN (-3900 2000) $PN BY2
J 0
(-3890 2010);
DISPLAY 0.489362 (-3890 2010);
PAINT MONO (-3890 2010);
FORCEPROP 0 LASTPIN (-3900 1950) $PN CA3
J 0
(-3890 1960);
DISPLAY 0.489362 (-3890 1960);
PAINT MONO (-3890 1960);
FORCEPROP 0 LASTPIN (-3900 1900) $PN CA2
J 0
(-3890 1910);
DISPLAY 0.489362 (-3890 1910);
PAINT MONO (-3890 1910);
FORCEPROP 0 LASTPIN (-3900 1850) $PN CB4
J 0
(-3890 1860);
DISPLAY 0.489362 (-3890 1860);
PAINT MONO (-3890 1860);
FORCEPROP 0 LASTPIN (-3900 1800) $PN BT2
J 0
(-3890 1810);
DISPLAY 0.489362 (-3890 1810);
PAINT MONO (-3890 1810);
FORCEPROP 0 LASTPIN (-3900 1750) $PN BU3
J 0
(-3890 1760);
DISPLAY 0.489362 (-3890 1760);
PAINT MONO (-3890 1760);
FORCEPROP 0 LASTPIN (-3900 1700) $PN BU2
J 0
(-3890 1710);
DISPLAY 0.489362 (-3890 1710);
PAINT MONO (-3890 1710);
FORCEPROP 0 LASTPIN (-3900 1650) $PN BV4
J 0
(-3890 1660);
DISPLAY 0.489362 (-3890 1660);
PAINT MONO (-3890 1660);
FORCEPROP 0 LASTPIN (-3900 4250) $PN CB2
J 0
(-3890 4260);
DISPLAY 0.489362 (-3890 4260);
PAINT MONO (-3890 4260);
FORCEPROP 0 LASTPIN (-3900 4200) $PN CC3
J 0
(-3890 4210);
DISPLAY 0.489362 (-3890 4210);
PAINT MONO (-3890 4210);
FORCEPROP 0 LASTPIN (-3900 4150) $PN CC2
J 0
(-3890 4160);
DISPLAY 0.489362 (-3890 4160);
PAINT MONO (-3890 4160);
FORCEPROP 0 LASTPIN (-3900 4100) $PN CD4
J 0
(-3890 4110);
DISPLAY 0.489362 (-3890 4110);
PAINT MONO (-3890 4110);
FORCEPROP 0 LASTPIN (-3900 4050) $PN CF2
J 0
(-3890 4060);
DISPLAY 0.489362 (-3890 4060);
PAINT MONO (-3890 4060);
FORCEPROP 0 LASTPIN (-3900 4000) $PN CG3
J 0
(-3890 4010);
DISPLAY 0.489362 (-3890 4010);
PAINT MONO (-3890 4010);
FORCEPROP 0 LASTPIN (-3900 3950) $PN CG2
J 0
(-3890 3960);
DISPLAY 0.489362 (-3890 3960);
PAINT MONO (-3890 3960);
FORCEPROP 0 LASTPIN (-3900 3900) $PN CH4
J 0
(-3890 3910);
DISPLAY 0.489362 (-3890 3910);
PAINT MONO (-3890 3910);
FORCEPROP 0 LASTPIN (-3900 3800) $PN CH2
J 0
(-3890 3810);
DISPLAY 0.489362 (-3890 3810);
PAINT MONO (-3890 3810);
FORCEPROP 0 LASTPIN (-3900 3750) $PN CJ3
J 0
(-3890 3760);
DISPLAY 0.489362 (-3890 3760);
PAINT MONO (-3890 3760);
FORCEPROP 0 LASTPIN (-3900 3700) $PN CJ2
J 0
(-3890 3710);
DISPLAY 0.489362 (-3890 3710);
PAINT MONO (-3890 3710);
FORCEPROP 0 LASTPIN (-3900 3650) $PN CK4
J 0
(-3890 3660);
DISPLAY 0.489362 (-3890 3660);
PAINT MONO (-3890 3660);
FORCEPROP 0 LASTPIN (-3900 3600) $PN CM2
J 0
(-3890 3610);
DISPLAY 0.489362 (-3890 3610);
PAINT MONO (-3890 3610);
FORCEPROP 0 LASTPIN (-3900 3550) $PN CN3
J 0
(-3890 3560);
DISPLAY 0.489362 (-3890 3560);
PAINT MONO (-3890 3560);
FORCEPROP 0 LASTPIN (-3900 3500) $PN CN2
J 0
(-3890 3510);
DISPLAY 0.489362 (-3890 3510);
PAINT MONO (-3890 3510);
FORCEPROP 0 LASTPIN (-3900 3450) $PN CP4
J 0
(-3890 3460);
DISPLAY 0.489362 (-3890 3460);
PAINT MONO (-3890 3460);
FORCEPROP 0 LASTPIN (-3900 3350) $PN CP2
J 0
(-3890 3360);
DISPLAY 0.489362 (-3890 3360);
PAINT MONO (-3890 3360);
FORCEPROP 0 LASTPIN (-3900 3300) $PN CR3
J 0
(-3890 3310);
DISPLAY 0.489362 (-3890 3310);
PAINT MONO (-3890 3310);
FORCEPROP 0 LASTPIN (-3900 3250) $PN CR2
J 0
(-3890 3260);
DISPLAY 0.489362 (-3890 3260);
PAINT MONO (-3890 3260);
FORCEPROP 0 LASTPIN (-3900 3200) $PN CT4
J 0
(-3890 3210);
DISPLAY 0.489362 (-3890 3210);
PAINT MONO (-3890 3210);
FORCEPROP 0 LASTPIN (-3900 3150) $PN CV2
J 0
(-3890 3160);
DISPLAY 0.489362 (-3890 3160);
PAINT MONO (-3890 3160);
FORCEPROP 0 LASTPIN (-3900 3100) $PN CW3
J 0
(-3890 3110);
DISPLAY 0.489362 (-3890 3110);
PAINT MONO (-3890 3110);
FORCEPROP 0 LASTPIN (-3900 3050) $PN CW2
J 0
(-3890 3060);
DISPLAY 0.489362 (-3890 3060);
PAINT MONO (-3890 3060);
FORCEPROP 0 LASTPIN (-3900 3000) $PN CY4
J 0
(-3890 3010);
DISPLAY 0.489362 (-3890 3010);
PAINT MONO (-3890 3010);
FORCEPROP 0 LASTPIN (-3900 2900) $PN CY2
J 0
(-3890 2910);
DISPLAY 0.489362 (-3890 2910);
PAINT MONO (-3890 2910);
FORCEPROP 0 LASTPIN (-3900 2850) $PN DA3
J 0
(-3890 2860);
DISPLAY 0.489362 (-3890 2860);
PAINT MONO (-3890 2860);
FORCEPROP 0 LASTPIN (-3900 2800) $PN DA2
J 0
(-3890 2810);
DISPLAY 0.489362 (-3890 2810);
PAINT MONO (-3890 2810);
FORCEPROP 0 LASTPIN (-3900 2750) $PN DB4
J 0
(-3890 2760);
DISPLAY 0.489362 (-3890 2760);
PAINT MONO (-3890 2760);
FORCEPROP 0 LASTPIN (-3900 2700) $PN DD2
J 0
(-3890 2710);
DISPLAY 0.489362 (-3890 2710);
PAINT MONO (-3890 2710);
FORCEPROP 0 LASTPIN (-3900 2650) $PN DE3
J 0
(-3890 2660);
DISPLAY 0.489362 (-3890 2660);
PAINT MONO (-3890 2660);
FORCEPROP 0 LASTPIN (-3900 2600) $PN DE2
J 0
(-3890 2610);
DISPLAY 0.489362 (-3890 2610);
PAINT MONO (-3890 2610);
FORCEPROP 0 LASTPIN (-3900 2550) $PN DF2
J 0
(-3890 2560);
DISPLAY 0.489362 (-3890 2560);
PAINT MONO (-3890 2560);
FORCEPROP 0 LASTPIN (-5500 5000) $PN CD2
J 2
(-5510 5010);
DISPLAY 0.489362 (-5510 5010);
PAINT MONO (-5510 5010);
FORCEPROP 0 LASTPIN (-5500 4900) $PN CK2
J 2
(-5510 4910);
DISPLAY 0.489362 (-5510 4910);
PAINT MONO (-5510 4910);
FORCEPROP 0 LASTPIN (-5500 4800) $PN CT2
J 2
(-5510 4810);
DISPLAY 0.489362 (-5510 4810);
PAINT MONO (-5510 4810);
FORCEPROP 0 LASTPIN (-5500 4700) $PN DB2
J 2
(-5510 4710);
DISPLAY 0.489362 (-5510 4710);
PAINT MONO (-5510 4710);
FORCEPROP 0 LASTPIN (-5500 4600) $PN BY4
J 2
(-5510 4610);
DISPLAY 0.489362 (-5510 4610);
PAINT MONO (-5510 4610);
FORCEPROP 0 LASTPIN (-5500 4500) $PN CF4
J 2
(-5510 4510);
DISPLAY 0.489362 (-5510 4510);
PAINT MONO (-5510 4510);
FORCEPROP 0 LASTPIN (-5500 4400) $PN CM4
J 2
(-5510 4410);
DISPLAY 0.489362 (-5510 4410);
PAINT MONO (-5510 4410);
FORCEPROP 0 LASTPIN (-5500 4300) $PN CV4
J 2
(-5510 4310);
DISPLAY 0.489362 (-5510 4310);
PAINT MONO (-5510 4310);
FORCEPROP 0 LASTPIN (-5500 4200) $PN DD4
J 2
(-5510 4210);
DISPLAY 0.489362 (-5510 4210);
PAINT MONO (-5510 4210);
FORCEPROP 0 LASTPIN (-5500 4100) $PN BV2
J 2
(-5510 4110);
DISPLAY 0.489362 (-5510 4110);
PAINT MONO (-5510 4110);
FORCEPROP 0 LASTPIN (-5500 4950) $PN CE2
J 2
(-5510 4960);
DISPLAY 0.489362 (-5510 4960);
PAINT MONO (-5510 4960);
FORCEPROP 0 LASTPIN (-5500 4850) $PN CL2
J 2
(-5510 4860);
DISPLAY 0.489362 (-5510 4860);
PAINT MONO (-5510 4860);
FORCEPROP 0 LASTPIN (-5500 4750) $PN CU2
J 2
(-5510 4760);
DISPLAY 0.489362 (-5510 4760);
PAINT MONO (-5510 4760);
FORCEPROP 0 LASTPIN (-5500 4650) $PN DC2
J 2
(-5510 4660);
DISPLAY 0.489362 (-5510 4660);
PAINT MONO (-5510 4660);
FORCEPROP 0 LASTPIN (-5500 4550) $PN BW3
J 2
(-5510 4560);
DISPLAY 0.489362 (-5510 4560);
PAINT MONO (-5510 4560);
FORCEPROP 0 LASTPIN (-5500 4450) $PN CE3
J 2
(-5510 4460);
DISPLAY 0.489362 (-5510 4460);
PAINT MONO (-5510 4460);
FORCEPROP 0 LASTPIN (-5500 4350) $PN CL3
J 2
(-5510 4360);
DISPLAY 0.489362 (-5510 4360);
PAINT MONO (-5510 4360);
FORCEPROP 0 LASTPIN (-5500 4250) $PN CU3
J 2
(-5510 4260);
DISPLAY 0.489362 (-5510 4260);
PAINT MONO (-5510 4260);
FORCEPROP 0 LASTPIN (-5500 4150) $PN DC3
J 2
(-5510 4160);
DISPLAY 0.489362 (-5510 4160);
PAINT MONO (-5510 4160);
FORCEPROP 0 LASTPIN (-5500 4050) $PN BW2
J 2
(-5510 4060);
DISPLAY 0.489362 (-5510 4060);
PAINT MONO (-5510 4060);
FORCEPROP 0 LASTPIN (-5500 2300) $PN BL3
J 2
(-5510 2310);
DISPLAY 0.489362 (-5510 2310);
PAINT MONO (-5510 2310);
FORCEPROP 0 LASTPIN (-5500 1250) $PN BF4
J 2
(-5510 1260);
DISPLAY 0.489362 (-5510 1260);
PAINT MONO (-5510 1260);
FORCEPROP 2 LAST PART_TYPE SMLF
J 0
(-5350 6425);
DISPLAY 1.021277 (-5350 6425);
FORCEPROP 1 LAST MATERIAL IO
J 0
(-5345 6232);
DISPLAY 0.489362 (-5345 6232);
PAINT SKYBLUE (-5345 6232);
FORCEPROP 2 LAST VALUE SOCKET6096_13568-001
J 0
(-5350 6325);
DISPLAY 0.489362 (-5350 6325);
PAINT SKYBLUE (-5350 6325);
FORCEPROP 1 LAST NEEDS_NO_SIZE TRUE
J 0
(-4700 3675);
DISPLAY 0.723404 (-4700 3675);
PAINT GREEN (-4700 3675);
DISPLAY INVISIBLE (-4700 3675);
FORCEPROP 1 LAST CDS_LMAN_SYM_OUTLINE -650,2525,650,-2525
J 0
(-4700 3675);
DISPLAY 0.468085 (-4700 3675);
PAINT GREEN (-4700 3675);
DISPLAY INVISIBLE (-4700 3675);
FORCEPROP 2 LAST CDS_LIB pure_quanta
J 0
(-4700 3675);
DISPLAY INVISIBLE (-4700 3675);
FORCEPROP 1 LAST PATH I167
J 0
(-4700 3675);
DISPLAY 0.723404 (-4700 3675);
PAINT GREEN (-4700 3675);
DISPLAY INVISIBLE (-4700 3675);
FORCEPROP 1 LAST PART_NUMBER DGA^6000030
J 0
(-5345 6359);
DISPLAY 0.489362 (-5345 6359);
PAINT SKYBLUE (-5345 6359);
DISPLAY INVISIBLE (-5345 6359);
FORCEADD OFFPAGE..3
(-2700 6075);
FORCEPROP 2 LAST $XR0 104 
J 0
(-2486 6075);
DISPLAY 0.638298 (-2486 6075);
PAINT MONO (-2486 6075);
FORCEPROP 2 LAST CDS_LIB mstr_standard
J 0
(-2700 6075);
DISPLAY 0.723404 (-2700 6075);
PAINT MONO (-2700 6075);
DISPLAY INVISIBLE (-2700 6075);
FORCEPROP 1 LAST OFFPAGE TRUE
J 0
(-2375 5950);
DISPLAY 0.872340 (-2375 5950);
PAINT GREEN (-2375 5950);
DISPLAY INVISIBLE (-2375 5950);
FORCEPROP 1 LAST COMMENT_BODY TRUE
J 0
(-2750 5975);
DISPLAY 0.872340 (-2750 5975);
PAINT GREEN (-2750 5975);
DISPLAY INVISIBLE (-2750 5975);
FORCEPROP 2 LAST PATH I168
J 0
(-2475 6125);
DISPLAY 1.021277 (-2475 6125);
DISPLAY INVISIBLE (-2475 6125);
FORCEADD OFFPAGE..3
(-2700 4275);
FORCEPROP 2 LAST $XR0 104 
J 0
(-2486 4275);
DISPLAY 0.638298 (-2486 4275);
PAINT MONO (-2486 4275);
FORCEPROP 2 LAST CDS_LIB mstr_standard
J 0
(-2700 4275);
DISPLAY 0.723404 (-2700 4275);
PAINT MONO (-2700 4275);
DISPLAY INVISIBLE (-2700 4275);
FORCEPROP 1 LAST OFFPAGE TRUE
J 0
(-2375 4150);
DISPLAY 0.872340 (-2375 4150);
PAINT GREEN (-2375 4150);
DISPLAY INVISIBLE (-2375 4150);
FORCEPROP 1 LAST COMMENT_BODY TRUE
J 0
(-2750 4175);
DISPLAY 0.872340 (-2750 4175);
PAINT GREEN (-2750 4175);
DISPLAY INVISIBLE (-2750 4175);
FORCEPROP 2 LAST PATH I169
J 0
(-2475 4325);
DISPLAY 1.021277 (-2475 4325);
DISPLAY INVISIBLE (-2475 4325);
FORCEADD TAP..1
(-3425 6050);
FORCEPROP 3 LASTPIN (-3475 6050) SIG_NAME M_G_CPU1_SA_DQ<0>
J 0
(-3465 6060);
DISPLAY 0.659574 (-3465 6060);
PAINT MONO (-3465 6060);
DISPLAY INVISIBLE (-3465 6060);
FORCEPROP 1 LASTPIN (-3475 6050) BN 0
J 0
(-3487 6058);
DISPLAY 0.489362 (-3487 6058);
PAINT GREEN (-3487 6058);
FORCEPROP 2 LAST CDS_LIB mstr_standard
J 0
(-3425 6050);
DISPLAY 0.723404 (-3425 6050);
PAINT MONO (-3425 6050);
DISPLAY INVISIBLE (-3425 6050);
FORCEPROP 1 LAST BODY_TYPE PLUMBING
J 0
(-3425 6100);
DISPLAY 0.872340 (-3425 6100);
PAINT GREEN (-3425 6100);
DISPLAY INVISIBLE (-3425 6100);
FORCEPROP 1 LAST HDL_TAP TRUE
J 0
(-3100 5925);
DISPLAY 0.872340 (-3100 5925);
DISPLAY INVISIBLE (-3100 5925);
FORCEPROP 1 LAST PATH I170
J 0
(-3427 6050);
DISPLAY 0.872340 (-3427 6050);
PAINT GREEN (-3427 6050);
DISPLAY INVISIBLE (-3427 6050);
FORCEADD TAP..1
(-3425 6000);
FORCEPROP 3 LASTPIN (-3475 6000) SIG_NAME M_G_CPU1_SA_DQ<1>
J 0
(-3465 6010);
DISPLAY 0.659574 (-3465 6010);
PAINT MONO (-3465 6010);
DISPLAY INVISIBLE (-3465 6010);
FORCEPROP 1 LASTPIN (-3475 6000) BN 1
J 0
(-3487 6008);
DISPLAY 0.489362 (-3487 6008);
PAINT GREEN (-3487 6008);
FORCEPROP 2 LAST CDS_LIB mstr_standard
J 0
(-3425 6000);
DISPLAY 0.723404 (-3425 6000);
PAINT MONO (-3425 6000);
DISPLAY INVISIBLE (-3425 6000);
FORCEPROP 1 LAST BODY_TYPE PLUMBING
J 0
(-3425 6050);
DISPLAY 0.872340 (-3425 6050);
PAINT GREEN (-3425 6050);
DISPLAY INVISIBLE (-3425 6050);
FORCEPROP 1 LAST HDL_TAP TRUE
J 0
(-3100 5875);
DISPLAY 0.872340 (-3100 5875);
DISPLAY INVISIBLE (-3100 5875);
FORCEPROP 1 LAST PATH I171
J 0
(-3427 6000);
DISPLAY 0.872340 (-3427 6000);
PAINT GREEN (-3427 6000);
DISPLAY INVISIBLE (-3427 6000);
FORCEADD TAP..1
(-3425 5900);
FORCEPROP 3 LASTPIN (-3475 5900) SIG_NAME M_G_CPU1_SA_DQ<3>
J 0
(-3465 5910);
DISPLAY 0.659574 (-3465 5910);
PAINT MONO (-3465 5910);
DISPLAY INVISIBLE (-3465 5910);
FORCEPROP 1 LASTPIN (-3475 5900) BN 3
J 0
(-3487 5908);
DISPLAY 0.489362 (-3487 5908);
PAINT GREEN (-3487 5908);
FORCEPROP 2 LAST CDS_LIB mstr_standard
J 0
(-3425 5900);
DISPLAY 0.723404 (-3425 5900);
PAINT MONO (-3425 5900);
DISPLAY INVISIBLE (-3425 5900);
FORCEPROP 1 LAST BODY_TYPE PLUMBING
J 0
(-3425 5950);
DISPLAY 0.872340 (-3425 5950);
PAINT GREEN (-3425 5950);
DISPLAY INVISIBLE (-3425 5950);
FORCEPROP 1 LAST HDL_TAP TRUE
J 0
(-3100 5775);
DISPLAY 0.872340 (-3100 5775);
DISPLAY INVISIBLE (-3100 5775);
FORCEPROP 1 LAST PATH I172
J 0
(-3427 5900);
DISPLAY 0.872340 (-3427 5900);
PAINT GREEN (-3427 5900);
DISPLAY INVISIBLE (-3427 5900);
FORCEADD TAP..1
(-3425 5950);
FORCEPROP 3 LASTPIN (-3475 5950) SIG_NAME M_G_CPU1_SA_DQ<2>
J 0
(-3465 5960);
DISPLAY 0.659574 (-3465 5960);
PAINT MONO (-3465 5960);
DISPLAY INVISIBLE (-3465 5960);
FORCEPROP 1 LASTPIN (-3475 5950) BN 2
J 0
(-3487 5958);
DISPLAY 0.489362 (-3487 5958);
PAINT GREEN (-3487 5958);
FORCEPROP 2 LAST CDS_LIB mstr_standard
J 0
(-3425 5950);
DISPLAY 0.723404 (-3425 5950);
PAINT MONO (-3425 5950);
DISPLAY INVISIBLE (-3425 5950);
FORCEPROP 1 LAST BODY_TYPE PLUMBING
J 0
(-3425 6000);
DISPLAY 0.872340 (-3425 6000);
PAINT GREEN (-3425 6000);
DISPLAY INVISIBLE (-3425 6000);
FORCEPROP 1 LAST HDL_TAP TRUE
J 0
(-3100 5825);
DISPLAY 0.872340 (-3100 5825);
DISPLAY INVISIBLE (-3100 5825);
FORCEPROP 1 LAST PATH I173
J 0
(-3427 5950);
DISPLAY 0.872340 (-3427 5950);
PAINT GREEN (-3427 5950);
DISPLAY INVISIBLE (-3427 5950);
FORCEADD TAP..1
(-3425 5850);
FORCEPROP 3 LASTPIN (-3475 5850) SIG_NAME M_G_CPU1_SA_DQ<4>
J 0
(-3465 5860);
DISPLAY 0.659574 (-3465 5860);
PAINT MONO (-3465 5860);
DISPLAY INVISIBLE (-3465 5860);
FORCEPROP 1 LASTPIN (-3475 5850) BN 4
J 0
(-3487 5858);
DISPLAY 0.489362 (-3487 5858);
PAINT GREEN (-3487 5858);
FORCEPROP 2 LAST CDS_LIB mstr_standard
J 0
(-3425 5850);
DISPLAY 0.723404 (-3425 5850);
PAINT MONO (-3425 5850);
DISPLAY INVISIBLE (-3425 5850);
FORCEPROP 1 LAST BODY_TYPE PLUMBING
J 0
(-3425 5900);
DISPLAY 0.872340 (-3425 5900);
PAINT GREEN (-3425 5900);
DISPLAY INVISIBLE (-3425 5900);
FORCEPROP 1 LAST HDL_TAP TRUE
J 0
(-3100 5725);
DISPLAY 0.872340 (-3100 5725);
DISPLAY INVISIBLE (-3100 5725);
FORCEPROP 1 LAST PATH I174
J 0
(-3427 5850);
DISPLAY 0.872340 (-3427 5850);
PAINT GREEN (-3427 5850);
DISPLAY INVISIBLE (-3427 5850);
FORCEADD TAP..1
(-3425 5800);
FORCEPROP 3 LASTPIN (-3475 5800) SIG_NAME M_G_CPU1_SA_DQ<5>
J 0
(-3465 5810);
DISPLAY 0.659574 (-3465 5810);
PAINT MONO (-3465 5810);
DISPLAY INVISIBLE (-3465 5810);
FORCEPROP 1 LASTPIN (-3475 5800) BN 5
J 0
(-3487 5808);
DISPLAY 0.489362 (-3487 5808);
PAINT GREEN (-3487 5808);
FORCEPROP 2 LAST CDS_LIB mstr_standard
J 0
(-3425 5800);
DISPLAY 0.723404 (-3425 5800);
PAINT MONO (-3425 5800);
DISPLAY INVISIBLE (-3425 5800);
FORCEPROP 1 LAST BODY_TYPE PLUMBING
J 0
(-3425 5850);
DISPLAY 0.872340 (-3425 5850);
PAINT GREEN (-3425 5850);
DISPLAY INVISIBLE (-3425 5850);
FORCEPROP 1 LAST HDL_TAP TRUE
J 0
(-3100 5675);
DISPLAY 0.872340 (-3100 5675);
DISPLAY INVISIBLE (-3100 5675);
FORCEPROP 1 LAST PATH I175
J 0
(-3427 5800);
DISPLAY 0.872340 (-3427 5800);
PAINT GREEN (-3427 5800);
DISPLAY INVISIBLE (-3427 5800);
FORCEADD TAP..1
(-3425 5750);
FORCEPROP 3 LASTPIN (-3475 5750) SIG_NAME M_G_CPU1_SA_DQ<6>
J 0
(-3465 5760);
DISPLAY 0.659574 (-3465 5760);
PAINT MONO (-3465 5760);
DISPLAY INVISIBLE (-3465 5760);
FORCEPROP 1 LASTPIN (-3475 5750) BN 6
J 0
(-3487 5758);
DISPLAY 0.489362 (-3487 5758);
PAINT GREEN (-3487 5758);
FORCEPROP 2 LAST CDS_LIB mstr_standard
J 0
(-3425 5750);
DISPLAY 0.723404 (-3425 5750);
PAINT MONO (-3425 5750);
DISPLAY INVISIBLE (-3425 5750);
FORCEPROP 1 LAST BODY_TYPE PLUMBING
J 0
(-3425 5800);
DISPLAY 0.872340 (-3425 5800);
PAINT GREEN (-3425 5800);
DISPLAY INVISIBLE (-3425 5800);
FORCEPROP 1 LAST HDL_TAP TRUE
J 0
(-3100 5625);
DISPLAY 0.872340 (-3100 5625);
DISPLAY INVISIBLE (-3100 5625);
FORCEPROP 1 LAST PATH I176
J 0
(-3427 5750);
DISPLAY 0.872340 (-3427 5750);
PAINT GREEN (-3427 5750);
DISPLAY INVISIBLE (-3427 5750);
FORCEADD TAP..1
(-3425 5700);
FORCEPROP 3 LASTPIN (-3475 5700) SIG_NAME M_G_CPU1_SA_DQ<7>
J 0
(-3465 5710);
DISPLAY 0.659574 (-3465 5710);
PAINT MONO (-3465 5710);
DISPLAY INVISIBLE (-3465 5710);
FORCEPROP 1 LASTPIN (-3475 5700) BN 7
J 0
(-3487 5708);
DISPLAY 0.489362 (-3487 5708);
PAINT GREEN (-3487 5708);
FORCEPROP 2 LAST CDS_LIB mstr_standard
J 0
(-3425 5700);
DISPLAY 0.723404 (-3425 5700);
PAINT MONO (-3425 5700);
DISPLAY INVISIBLE (-3425 5700);
FORCEPROP 1 LAST BODY_TYPE PLUMBING
J 0
(-3425 5750);
DISPLAY 0.872340 (-3425 5750);
PAINT GREEN (-3425 5750);
DISPLAY INVISIBLE (-3425 5750);
FORCEPROP 1 LAST HDL_TAP TRUE
J 0
(-3100 5575);
DISPLAY 0.872340 (-3100 5575);
DISPLAY INVISIBLE (-3100 5575);
FORCEPROP 1 LAST PATH I177
J 0
(-3427 5700);
DISPLAY 0.872340 (-3427 5700);
PAINT GREEN (-3427 5700);
DISPLAY INVISIBLE (-3427 5700);
FORCEADD TAP..1
(-3425 5600);
FORCEPROP 3 LASTPIN (-3475 5600) SIG_NAME M_G_CPU1_SA_DQ<8>
J 0
(-3465 5610);
DISPLAY 0.659574 (-3465 5610);
PAINT MONO (-3465 5610);
DISPLAY INVISIBLE (-3465 5610);
FORCEPROP 1 LASTPIN (-3475 5600) BN 8
J 0
(-3487 5608);
DISPLAY 0.489362 (-3487 5608);
PAINT GREEN (-3487 5608);
FORCEPROP 2 LAST CDS_LIB mstr_standard
J 0
(-3425 5600);
DISPLAY 0.723404 (-3425 5600);
PAINT MONO (-3425 5600);
DISPLAY INVISIBLE (-3425 5600);
FORCEPROP 1 LAST BODY_TYPE PLUMBING
J 0
(-3425 5650);
DISPLAY 0.872340 (-3425 5650);
PAINT GREEN (-3425 5650);
DISPLAY INVISIBLE (-3425 5650);
FORCEPROP 1 LAST HDL_TAP TRUE
J 0
(-3100 5475);
DISPLAY 0.872340 (-3100 5475);
DISPLAY INVISIBLE (-3100 5475);
FORCEPROP 1 LAST PATH I178
J 0
(-3427 5600);
DISPLAY 0.872340 (-3427 5600);
PAINT GREEN (-3427 5600);
DISPLAY INVISIBLE (-3427 5600);
FORCEADD TAP..1
(-3425 5550);
FORCEPROP 3 LASTPIN (-3475 5550) SIG_NAME M_G_CPU1_SA_DQ<9>
J 0
(-3465 5560);
DISPLAY 0.659574 (-3465 5560);
PAINT MONO (-3465 5560);
DISPLAY INVISIBLE (-3465 5560);
FORCEPROP 1 LASTPIN (-3475 5550) BN 9
J 0
(-3487 5558);
DISPLAY 0.489362 (-3487 5558);
PAINT GREEN (-3487 5558);
FORCEPROP 2 LAST CDS_LIB mstr_standard
J 0
(-3425 5550);
DISPLAY 0.723404 (-3425 5550);
PAINT MONO (-3425 5550);
DISPLAY INVISIBLE (-3425 5550);
FORCEPROP 1 LAST BODY_TYPE PLUMBING
J 0
(-3425 5600);
DISPLAY 0.872340 (-3425 5600);
PAINT GREEN (-3425 5600);
DISPLAY INVISIBLE (-3425 5600);
FORCEPROP 1 LAST HDL_TAP TRUE
J 0
(-3100 5425);
DISPLAY 0.872340 (-3100 5425);
DISPLAY INVISIBLE (-3100 5425);
FORCEPROP 1 LAST PATH I179
J 0
(-3427 5550);
DISPLAY 0.872340 (-3427 5550);
PAINT GREEN (-3427 5550);
DISPLAY INVISIBLE (-3427 5550);
FORCEADD TAP..1
(-3425 5500);
FORCEPROP 3 LASTPIN (-3475 5500) SIG_NAME M_G_CPU1_SA_DQ<10>
J 0
(-3465 5510);
DISPLAY 0.659574 (-3465 5510);
PAINT MONO (-3465 5510);
DISPLAY INVISIBLE (-3465 5510);
FORCEPROP 1 LASTPIN (-3475 5500) BN 10
J 0
(-3487 5508);
DISPLAY 0.489362 (-3487 5508);
PAINT GREEN (-3487 5508);
FORCEPROP 2 LAST CDS_LIB mstr_standard
J 0
(-3425 5500);
DISPLAY 0.723404 (-3425 5500);
PAINT MONO (-3425 5500);
DISPLAY INVISIBLE (-3425 5500);
FORCEPROP 1 LAST BODY_TYPE PLUMBING
J 0
(-3425 5550);
DISPLAY 0.872340 (-3425 5550);
PAINT GREEN (-3425 5550);
DISPLAY INVISIBLE (-3425 5550);
FORCEPROP 1 LAST HDL_TAP TRUE
J 0
(-3100 5375);
DISPLAY 0.872340 (-3100 5375);
DISPLAY INVISIBLE (-3100 5375);
FORCEPROP 1 LAST PATH I180
J 0
(-3427 5500);
DISPLAY 0.872340 (-3427 5500);
PAINT GREEN (-3427 5500);
DISPLAY INVISIBLE (-3427 5500);
FORCEADD TAP..1
(-3425 5450);
FORCEPROP 3 LASTPIN (-3475 5450) SIG_NAME M_G_CPU1_SA_DQ<11>
J 0
(-3465 5460);
DISPLAY 0.659574 (-3465 5460);
PAINT MONO (-3465 5460);
DISPLAY INVISIBLE (-3465 5460);
FORCEPROP 1 LASTPIN (-3475 5450) BN 11
J 0
(-3487 5458);
DISPLAY 0.489362 (-3487 5458);
PAINT GREEN (-3487 5458);
FORCEPROP 2 LAST CDS_LIB mstr_standard
J 0
(-3425 5450);
DISPLAY 0.723404 (-3425 5450);
PAINT MONO (-3425 5450);
DISPLAY INVISIBLE (-3425 5450);
FORCEPROP 1 LAST BODY_TYPE PLUMBING
J 0
(-3425 5500);
DISPLAY 0.872340 (-3425 5500);
PAINT GREEN (-3425 5500);
DISPLAY INVISIBLE (-3425 5500);
FORCEPROP 1 LAST HDL_TAP TRUE
J 0
(-3100 5325);
DISPLAY 0.872340 (-3100 5325);
DISPLAY INVISIBLE (-3100 5325);
FORCEPROP 1 LAST PATH I181
J 0
(-3427 5450);
DISPLAY 0.872340 (-3427 5450);
PAINT GREEN (-3427 5450);
DISPLAY INVISIBLE (-3427 5450);
FORCEADD TAP..1
(-3425 5400);
FORCEPROP 3 LASTPIN (-3475 5400) SIG_NAME M_G_CPU1_SA_DQ<12>
J 0
(-3465 5410);
DISPLAY 0.659574 (-3465 5410);
PAINT MONO (-3465 5410);
DISPLAY INVISIBLE (-3465 5410);
FORCEPROP 1 LASTPIN (-3475 5400) BN 12
J 0
(-3487 5408);
DISPLAY 0.489362 (-3487 5408);
PAINT GREEN (-3487 5408);
FORCEPROP 2 LAST CDS_LIB mstr_standard
J 0
(-3425 5400);
DISPLAY 0.723404 (-3425 5400);
PAINT MONO (-3425 5400);
DISPLAY INVISIBLE (-3425 5400);
FORCEPROP 1 LAST BODY_TYPE PLUMBING
J 0
(-3425 5450);
DISPLAY 0.872340 (-3425 5450);
PAINT GREEN (-3425 5450);
DISPLAY INVISIBLE (-3425 5450);
FORCEPROP 1 LAST HDL_TAP TRUE
J 0
(-3100 5275);
DISPLAY 0.872340 (-3100 5275);
DISPLAY INVISIBLE (-3100 5275);
FORCEPROP 1 LAST PATH I182
J 0
(-3427 5400);
DISPLAY 0.872340 (-3427 5400);
PAINT GREEN (-3427 5400);
DISPLAY INVISIBLE (-3427 5400);
FORCEADD TAP..1
(-3425 5350);
FORCEPROP 3 LASTPIN (-3475 5350) SIG_NAME M_G_CPU1_SA_DQ<13>
J 0
(-3465 5360);
DISPLAY 0.659574 (-3465 5360);
PAINT MONO (-3465 5360);
DISPLAY INVISIBLE (-3465 5360);
FORCEPROP 1 LASTPIN (-3475 5350) BN 13
J 0
(-3487 5358);
DISPLAY 0.489362 (-3487 5358);
PAINT GREEN (-3487 5358);
FORCEPROP 2 LAST CDS_LIB mstr_standard
J 0
(-3425 5350);
DISPLAY 0.723404 (-3425 5350);
PAINT MONO (-3425 5350);
DISPLAY INVISIBLE (-3425 5350);
FORCEPROP 1 LAST BODY_TYPE PLUMBING
J 0
(-3425 5400);
DISPLAY 0.872340 (-3425 5400);
PAINT GREEN (-3425 5400);
DISPLAY INVISIBLE (-3425 5400);
FORCEPROP 1 LAST HDL_TAP TRUE
J 0
(-3100 5225);
DISPLAY 0.872340 (-3100 5225);
DISPLAY INVISIBLE (-3100 5225);
FORCEPROP 1 LAST PATH I183
J 0
(-3427 5350);
DISPLAY 0.872340 (-3427 5350);
PAINT GREEN (-3427 5350);
DISPLAY INVISIBLE (-3427 5350);
FORCEADD TAP..1
(-3425 5250);
FORCEPROP 3 LASTPIN (-3475 5250) SIG_NAME M_G_CPU1_SA_DQ<15>
J 0
(-3465 5260);
DISPLAY 0.659574 (-3465 5260);
PAINT MONO (-3465 5260);
DISPLAY INVISIBLE (-3465 5260);
FORCEPROP 1 LASTPIN (-3475 5250) BN 15
J 0
(-3487 5258);
DISPLAY 0.489362 (-3487 5258);
PAINT GREEN (-3487 5258);
FORCEPROP 2 LAST CDS_LIB mstr_standard
J 0
(-3425 5250);
DISPLAY 0.723404 (-3425 5250);
PAINT MONO (-3425 5250);
DISPLAY INVISIBLE (-3425 5250);
FORCEPROP 1 LAST BODY_TYPE PLUMBING
J 0
(-3425 5300);
DISPLAY 0.872340 (-3425 5300);
PAINT GREEN (-3425 5300);
DISPLAY INVISIBLE (-3425 5300);
FORCEPROP 1 LAST HDL_TAP TRUE
J 0
(-3100 5125);
DISPLAY 0.872340 (-3100 5125);
DISPLAY INVISIBLE (-3100 5125);
FORCEPROP 1 LAST PATH I184
J 0
(-3427 5250);
DISPLAY 0.872340 (-3427 5250);
PAINT GREEN (-3427 5250);
DISPLAY INVISIBLE (-3427 5250);
FORCEADD TAP..1
(-3425 5300);
FORCEPROP 3 LASTPIN (-3475 5300) SIG_NAME M_G_CPU1_SA_DQ<14>
J 0
(-3465 5310);
DISPLAY 0.659574 (-3465 5310);
PAINT MONO (-3465 5310);
DISPLAY INVISIBLE (-3465 5310);
FORCEPROP 1 LASTPIN (-3475 5300) BN 14
J 0
(-3487 5308);
DISPLAY 0.489362 (-3487 5308);
PAINT GREEN (-3487 5308);
FORCEPROP 2 LAST CDS_LIB mstr_standard
J 0
(-3425 5300);
DISPLAY 0.723404 (-3425 5300);
PAINT MONO (-3425 5300);
DISPLAY INVISIBLE (-3425 5300);
FORCEPROP 1 LAST BODY_TYPE PLUMBING
J 0
(-3425 5350);
DISPLAY 0.872340 (-3425 5350);
PAINT GREEN (-3425 5350);
DISPLAY INVISIBLE (-3425 5350);
FORCEPROP 1 LAST HDL_TAP TRUE
J 0
(-3100 5175);
DISPLAY 0.872340 (-3100 5175);
DISPLAY INVISIBLE (-3100 5175);
FORCEPROP 1 LAST PATH I185
J 0
(-3427 5300);
DISPLAY 0.872340 (-3427 5300);
PAINT GREEN (-3427 5300);
DISPLAY INVISIBLE (-3427 5300);
FORCEADD TAP..1
(-3425 5150);
FORCEPROP 3 LASTPIN (-3475 5150) SIG_NAME M_G_CPU1_SA_DQ<16>
J 0
(-3465 5160);
DISPLAY 0.659574 (-3465 5160);
PAINT MONO (-3465 5160);
DISPLAY INVISIBLE (-3465 5160);
FORCEPROP 1 LASTPIN (-3475 5150) BN 16
J 0
(-3487 5158);
DISPLAY 0.489362 (-3487 5158);
PAINT GREEN (-3487 5158);
FORCEPROP 2 LAST CDS_LIB mstr_standard
J 0
(-3425 5150);
DISPLAY 0.723404 (-3425 5150);
PAINT MONO (-3425 5150);
DISPLAY INVISIBLE (-3425 5150);
FORCEPROP 1 LAST BODY_TYPE PLUMBING
J 0
(-3425 5200);
DISPLAY 0.872340 (-3425 5200);
PAINT GREEN (-3425 5200);
DISPLAY INVISIBLE (-3425 5200);
FORCEPROP 1 LAST HDL_TAP TRUE
J 0
(-3100 5025);
DISPLAY 0.872340 (-3100 5025);
DISPLAY INVISIBLE (-3100 5025);
FORCEPROP 1 LAST PATH I186
J 0
(-3427 5150);
DISPLAY 0.872340 (-3427 5150);
PAINT GREEN (-3427 5150);
DISPLAY INVISIBLE (-3427 5150);
FORCEADD TAP..1
(-3425 5100);
FORCEPROP 3 LASTPIN (-3475 5100) SIG_NAME M_G_CPU1_SA_DQ<17>
J 0
(-3465 5110);
DISPLAY 0.659574 (-3465 5110);
PAINT MONO (-3465 5110);
DISPLAY INVISIBLE (-3465 5110);
FORCEPROP 1 LASTPIN (-3475 5100) BN 17
J 0
(-3487 5108);
DISPLAY 0.489362 (-3487 5108);
PAINT GREEN (-3487 5108);
FORCEPROP 2 LAST CDS_LIB mstr_standard
J 0
(-3425 5100);
DISPLAY 0.723404 (-3425 5100);
PAINT MONO (-3425 5100);
DISPLAY INVISIBLE (-3425 5100);
FORCEPROP 1 LAST BODY_TYPE PLUMBING
J 0
(-3425 5150);
DISPLAY 0.872340 (-3425 5150);
PAINT GREEN (-3425 5150);
DISPLAY INVISIBLE (-3425 5150);
FORCEPROP 1 LAST HDL_TAP TRUE
J 0
(-3100 4975);
DISPLAY 0.872340 (-3100 4975);
DISPLAY INVISIBLE (-3100 4975);
FORCEPROP 1 LAST PATH I187
J 0
(-3427 5100);
DISPLAY 0.872340 (-3427 5100);
PAINT GREEN (-3427 5100);
DISPLAY INVISIBLE (-3427 5100);
FORCEADD TAP..1
(-3425 5000);
FORCEPROP 3 LASTPIN (-3475 5000) SIG_NAME M_G_CPU1_SA_DQ<19>
J 0
(-3465 5010);
DISPLAY 0.659574 (-3465 5010);
PAINT MONO (-3465 5010);
DISPLAY INVISIBLE (-3465 5010);
FORCEPROP 1 LASTPIN (-3475 5000) BN 19
J 0
(-3487 5008);
DISPLAY 0.489362 (-3487 5008);
PAINT GREEN (-3487 5008);
FORCEPROP 2 LAST CDS_LIB mstr_standard
J 0
(-3425 5000);
DISPLAY 0.723404 (-3425 5000);
PAINT MONO (-3425 5000);
DISPLAY INVISIBLE (-3425 5000);
FORCEPROP 1 LAST BODY_TYPE PLUMBING
J 0
(-3425 5050);
DISPLAY 0.872340 (-3425 5050);
PAINT GREEN (-3425 5050);
DISPLAY INVISIBLE (-3425 5050);
FORCEPROP 1 LAST HDL_TAP TRUE
J 0
(-3100 4875);
DISPLAY 0.872340 (-3100 4875);
DISPLAY INVISIBLE (-3100 4875);
FORCEPROP 1 LAST PATH I188
J 0
(-3427 5000);
DISPLAY 0.872340 (-3427 5000);
PAINT GREEN (-3427 5000);
DISPLAY INVISIBLE (-3427 5000);
FORCEADD TAP..1
(-3425 5050);
FORCEPROP 3 LASTPIN (-3475 5050) SIG_NAME M_G_CPU1_SA_DQ<18>
J 0
(-3465 5060);
DISPLAY 0.659574 (-3465 5060);
PAINT MONO (-3465 5060);
DISPLAY INVISIBLE (-3465 5060);
FORCEPROP 1 LASTPIN (-3475 5050) BN 18
J 0
(-3487 5058);
DISPLAY 0.489362 (-3487 5058);
PAINT GREEN (-3487 5058);
FORCEPROP 2 LAST CDS_LIB mstr_standard
J 0
(-3425 5050);
DISPLAY 0.723404 (-3425 5050);
PAINT MONO (-3425 5050);
DISPLAY INVISIBLE (-3425 5050);
FORCEPROP 1 LAST BODY_TYPE PLUMBING
J 0
(-3425 5100);
DISPLAY 0.872340 (-3425 5100);
PAINT GREEN (-3425 5100);
DISPLAY INVISIBLE (-3425 5100);
FORCEPROP 1 LAST HDL_TAP TRUE
J 0
(-3100 4925);
DISPLAY 0.872340 (-3100 4925);
DISPLAY INVISIBLE (-3100 4925);
FORCEPROP 1 LAST PATH I189
J 0
(-3427 5050);
DISPLAY 0.872340 (-3427 5050);
PAINT GREEN (-3427 5050);
DISPLAY INVISIBLE (-3427 5050);
FORCEADD TAP..1
(-3425 4950);
FORCEPROP 3 LASTPIN (-3475 4950) SIG_NAME M_G_CPU1_SA_DQ<20>
J 0
(-3465 4960);
DISPLAY 0.659574 (-3465 4960);
PAINT MONO (-3465 4960);
DISPLAY INVISIBLE (-3465 4960);
FORCEPROP 1 LASTPIN (-3475 4950) BN 20
J 0
(-3487 4958);
DISPLAY 0.489362 (-3487 4958);
PAINT GREEN (-3487 4958);
FORCEPROP 2 LAST CDS_LIB mstr_standard
J 0
(-3425 4950);
DISPLAY 0.723404 (-3425 4950);
PAINT MONO (-3425 4950);
DISPLAY INVISIBLE (-3425 4950);
FORCEPROP 1 LAST BODY_TYPE PLUMBING
J 0
(-3425 5000);
DISPLAY 0.872340 (-3425 5000);
PAINT GREEN (-3425 5000);
DISPLAY INVISIBLE (-3425 5000);
FORCEPROP 1 LAST HDL_TAP TRUE
J 0
(-3100 4825);
DISPLAY 0.872340 (-3100 4825);
DISPLAY INVISIBLE (-3100 4825);
FORCEPROP 1 LAST PATH I190
J 0
(-3427 4950);
DISPLAY 0.872340 (-3427 4950);
PAINT GREEN (-3427 4950);
DISPLAY INVISIBLE (-3427 4950);
FORCEADD TAP..1
(-3425 4900);
FORCEPROP 3 LASTPIN (-3475 4900) SIG_NAME M_G_CPU1_SA_DQ<21>
J 0
(-3465 4910);
DISPLAY 0.659574 (-3465 4910);
PAINT MONO (-3465 4910);
DISPLAY INVISIBLE (-3465 4910);
FORCEPROP 1 LASTPIN (-3475 4900) BN 21
J 0
(-3487 4908);
DISPLAY 0.489362 (-3487 4908);
PAINT GREEN (-3487 4908);
FORCEPROP 2 LAST CDS_LIB mstr_standard
J 0
(-3425 4900);
DISPLAY 0.723404 (-3425 4900);
PAINT MONO (-3425 4900);
DISPLAY INVISIBLE (-3425 4900);
FORCEPROP 1 LAST BODY_TYPE PLUMBING
J 0
(-3425 4950);
DISPLAY 0.872340 (-3425 4950);
PAINT GREEN (-3425 4950);
DISPLAY INVISIBLE (-3425 4950);
FORCEPROP 1 LAST HDL_TAP TRUE
J 0
(-3100 4775);
DISPLAY 0.872340 (-3100 4775);
DISPLAY INVISIBLE (-3100 4775);
FORCEPROP 1 LAST PATH I191
J 0
(-3427 4900);
DISPLAY 0.872340 (-3427 4900);
PAINT GREEN (-3427 4900);
DISPLAY INVISIBLE (-3427 4900);
FORCEADD TAP..1
(-3425 4850);
FORCEPROP 3 LASTPIN (-3475 4850) SIG_NAME M_G_CPU1_SA_DQ<22>
J 0
(-3465 4860);
DISPLAY 0.659574 (-3465 4860);
PAINT MONO (-3465 4860);
DISPLAY INVISIBLE (-3465 4860);
FORCEPROP 1 LASTPIN (-3475 4850) BN 22
J 0
(-3487 4858);
DISPLAY 0.489362 (-3487 4858);
PAINT GREEN (-3487 4858);
FORCEPROP 2 LAST CDS_LIB mstr_standard
J 0
(-3425 4850);
DISPLAY 0.723404 (-3425 4850);
PAINT MONO (-3425 4850);
DISPLAY INVISIBLE (-3425 4850);
FORCEPROP 1 LAST BODY_TYPE PLUMBING
J 0
(-3425 4900);
DISPLAY 0.872340 (-3425 4900);
PAINT GREEN (-3425 4900);
DISPLAY INVISIBLE (-3425 4900);
FORCEPROP 1 LAST HDL_TAP TRUE
J 0
(-3100 4725);
DISPLAY 0.872340 (-3100 4725);
DISPLAY INVISIBLE (-3100 4725);
FORCEPROP 1 LAST PATH I192
J 0
(-3427 4850);
DISPLAY 0.872340 (-3427 4850);
PAINT GREEN (-3427 4850);
DISPLAY INVISIBLE (-3427 4850);
FORCEADD TAP..1
(-3425 4800);
FORCEPROP 3 LASTPIN (-3475 4800) SIG_NAME M_G_CPU1_SA_DQ<23>
J 0
(-3465 4810);
DISPLAY 0.659574 (-3465 4810);
PAINT MONO (-3465 4810);
DISPLAY INVISIBLE (-3465 4810);
FORCEPROP 1 LASTPIN (-3475 4800) BN 23
J 0
(-3487 4808);
DISPLAY 0.489362 (-3487 4808);
PAINT GREEN (-3487 4808);
FORCEPROP 2 LAST CDS_LIB mstr_standard
J 0
(-3425 4800);
DISPLAY 0.723404 (-3425 4800);
PAINT MONO (-3425 4800);
DISPLAY INVISIBLE (-3425 4800);
FORCEPROP 1 LAST BODY_TYPE PLUMBING
J 0
(-3425 4850);
DISPLAY 0.872340 (-3425 4850);
PAINT GREEN (-3425 4850);
DISPLAY INVISIBLE (-3425 4850);
FORCEPROP 1 LAST HDL_TAP TRUE
J 0
(-3100 4675);
DISPLAY 0.872340 (-3100 4675);
DISPLAY INVISIBLE (-3100 4675);
FORCEPROP 1 LAST PATH I193
J 0
(-3427 4800);
DISPLAY 0.872340 (-3427 4800);
PAINT GREEN (-3427 4800);
DISPLAY INVISIBLE (-3427 4800);
FORCEADD TAP..1
(-3425 4700);
FORCEPROP 3 LASTPIN (-3475 4700) SIG_NAME M_G_CPU1_SA_DQ<24>
J 0
(-3465 4710);
DISPLAY 0.659574 (-3465 4710);
PAINT MONO (-3465 4710);
DISPLAY INVISIBLE (-3465 4710);
FORCEPROP 1 LASTPIN (-3475 4700) BN 24
J 0
(-3487 4708);
DISPLAY 0.489362 (-3487 4708);
PAINT GREEN (-3487 4708);
FORCEPROP 2 LAST CDS_LIB mstr_standard
J 0
(-3425 4700);
DISPLAY 0.723404 (-3425 4700);
PAINT MONO (-3425 4700);
DISPLAY INVISIBLE (-3425 4700);
FORCEPROP 1 LAST BODY_TYPE PLUMBING
J 0
(-3425 4750);
DISPLAY 0.872340 (-3425 4750);
PAINT GREEN (-3425 4750);
DISPLAY INVISIBLE (-3425 4750);
FORCEPROP 1 LAST HDL_TAP TRUE
J 0
(-3100 4575);
DISPLAY 0.872340 (-3100 4575);
DISPLAY INVISIBLE (-3100 4575);
FORCEPROP 1 LAST PATH I194
J 0
(-3427 4700);
DISPLAY 0.872340 (-3427 4700);
PAINT GREEN (-3427 4700);
DISPLAY INVISIBLE (-3427 4700);
FORCEADD TAP..1
(-3425 4650);
FORCEPROP 3 LASTPIN (-3475 4650) SIG_NAME M_G_CPU1_SA_DQ<25>
J 0
(-3465 4660);
DISPLAY 0.659574 (-3465 4660);
PAINT MONO (-3465 4660);
DISPLAY INVISIBLE (-3465 4660);
FORCEPROP 1 LASTPIN (-3475 4650) BN 25
J 0
(-3487 4658);
DISPLAY 0.489362 (-3487 4658);
PAINT GREEN (-3487 4658);
FORCEPROP 2 LAST CDS_LIB mstr_standard
J 0
(-3425 4650);
DISPLAY 0.723404 (-3425 4650);
PAINT MONO (-3425 4650);
DISPLAY INVISIBLE (-3425 4650);
FORCEPROP 1 LAST BODY_TYPE PLUMBING
J 0
(-3425 4700);
DISPLAY 0.872340 (-3425 4700);
PAINT GREEN (-3425 4700);
DISPLAY INVISIBLE (-3425 4700);
FORCEPROP 1 LAST HDL_TAP TRUE
J 0
(-3100 4525);
DISPLAY 0.872340 (-3100 4525);
DISPLAY INVISIBLE (-3100 4525);
FORCEPROP 1 LAST PATH I195
J 0
(-3427 4650);
DISPLAY 0.872340 (-3427 4650);
PAINT GREEN (-3427 4650);
DISPLAY INVISIBLE (-3427 4650);
FORCEADD TAP..1
(-3425 4600);
FORCEPROP 3 LASTPIN (-3475 4600) SIG_NAME M_G_CPU1_SA_DQ<26>
J 0
(-3465 4610);
DISPLAY 0.659574 (-3465 4610);
PAINT MONO (-3465 4610);
DISPLAY INVISIBLE (-3465 4610);
FORCEPROP 1 LASTPIN (-3475 4600) BN 26
J 0
(-3487 4608);
DISPLAY 0.489362 (-3487 4608);
PAINT GREEN (-3487 4608);
FORCEPROP 2 LAST CDS_LIB mstr_standard
J 0
(-3425 4600);
DISPLAY 0.723404 (-3425 4600);
PAINT MONO (-3425 4600);
DISPLAY INVISIBLE (-3425 4600);
FORCEPROP 1 LAST BODY_TYPE PLUMBING
J 0
(-3425 4650);
DISPLAY 0.872340 (-3425 4650);
PAINT GREEN (-3425 4650);
DISPLAY INVISIBLE (-3425 4650);
FORCEPROP 1 LAST HDL_TAP TRUE
J 0
(-3100 4475);
DISPLAY 0.872340 (-3100 4475);
DISPLAY INVISIBLE (-3100 4475);
FORCEPROP 1 LAST PATH I196
J 0
(-3427 4600);
DISPLAY 0.872340 (-3427 4600);
PAINT GREEN (-3427 4600);
DISPLAY INVISIBLE (-3427 4600);
FORCEADD TAP..1
(-3425 4550);
FORCEPROP 3 LASTPIN (-3475 4550) SIG_NAME M_G_CPU1_SA_DQ<27>
J 0
(-3465 4560);
DISPLAY 0.659574 (-3465 4560);
PAINT MONO (-3465 4560);
DISPLAY INVISIBLE (-3465 4560);
FORCEPROP 1 LASTPIN (-3475 4550) BN 27
J 0
(-3487 4558);
DISPLAY 0.489362 (-3487 4558);
PAINT GREEN (-3487 4558);
FORCEPROP 2 LAST CDS_LIB mstr_standard
J 0
(-3425 4550);
DISPLAY 0.723404 (-3425 4550);
PAINT MONO (-3425 4550);
DISPLAY INVISIBLE (-3425 4550);
FORCEPROP 1 LAST BODY_TYPE PLUMBING
J 0
(-3425 4600);
DISPLAY 0.872340 (-3425 4600);
PAINT GREEN (-3425 4600);
DISPLAY INVISIBLE (-3425 4600);
FORCEPROP 1 LAST HDL_TAP TRUE
J 0
(-3100 4425);
DISPLAY 0.872340 (-3100 4425);
DISPLAY INVISIBLE (-3100 4425);
FORCEPROP 1 LAST PATH I197
J 0
(-3427 4550);
DISPLAY 0.872340 (-3427 4550);
PAINT GREEN (-3427 4550);
DISPLAY INVISIBLE (-3427 4550);
FORCEADD TAP..1
(-3425 4500);
FORCEPROP 3 LASTPIN (-3475 4500) SIG_NAME M_G_CPU1_SA_DQ<28>
J 0
(-3465 4510);
DISPLAY 0.659574 (-3465 4510);
PAINT MONO (-3465 4510);
DISPLAY INVISIBLE (-3465 4510);
FORCEPROP 1 LASTPIN (-3475 4500) BN 28
J 0
(-3487 4508);
DISPLAY 0.489362 (-3487 4508);
PAINT GREEN (-3487 4508);
FORCEPROP 2 LAST CDS_LIB mstr_standard
J 0
(-3425 4500);
DISPLAY 0.723404 (-3425 4500);
PAINT MONO (-3425 4500);
DISPLAY INVISIBLE (-3425 4500);
FORCEPROP 1 LAST BODY_TYPE PLUMBING
J 0
(-3425 4550);
DISPLAY 0.872340 (-3425 4550);
PAINT GREEN (-3425 4550);
DISPLAY INVISIBLE (-3425 4550);
FORCEPROP 1 LAST HDL_TAP TRUE
J 0
(-3100 4375);
DISPLAY 0.872340 (-3100 4375);
DISPLAY INVISIBLE (-3100 4375);
FORCEPROP 1 LAST PATH I198
J 0
(-3427 4500);
DISPLAY 0.872340 (-3427 4500);
PAINT GREEN (-3427 4500);
DISPLAY INVISIBLE (-3427 4500);
FORCEADD TAP..1
(-3425 4450);
FORCEPROP 3 LASTPIN (-3475 4450) SIG_NAME M_G_CPU1_SA_DQ<29>
J 0
(-3465 4460);
DISPLAY 0.659574 (-3465 4460);
PAINT MONO (-3465 4460);
DISPLAY INVISIBLE (-3465 4460);
FORCEPROP 1 LASTPIN (-3475 4450) BN 29
J 0
(-3487 4458);
DISPLAY 0.489362 (-3487 4458);
PAINT GREEN (-3487 4458);
FORCEPROP 2 LAST CDS_LIB mstr_standard
J 0
(-3425 4450);
DISPLAY 0.723404 (-3425 4450);
PAINT MONO (-3425 4450);
DISPLAY INVISIBLE (-3425 4450);
FORCEPROP 1 LAST BODY_TYPE PLUMBING
J 0
(-3425 4500);
DISPLAY 0.872340 (-3425 4500);
PAINT GREEN (-3425 4500);
DISPLAY INVISIBLE (-3425 4500);
FORCEPROP 1 LAST HDL_TAP TRUE
J 0
(-3100 4325);
DISPLAY 0.872340 (-3100 4325);
DISPLAY INVISIBLE (-3100 4325);
FORCEPROP 1 LAST PATH I199
J 0
(-3427 4450);
DISPLAY 0.872340 (-3427 4450);
PAINT GREEN (-3427 4450);
DISPLAY INVISIBLE (-3427 4450);
FORCEADD TAP..1
(-3425 4400);
FORCEPROP 3 LASTPIN (-3475 4400) SIG_NAME M_G_CPU1_SA_DQ<30>
J 0
(-3465 4410);
DISPLAY 0.659574 (-3465 4410);
PAINT MONO (-3465 4410);
DISPLAY INVISIBLE (-3465 4410);
FORCEPROP 1 LASTPIN (-3475 4400) BN 30
J 0
(-3487 4408);
DISPLAY 0.489362 (-3487 4408);
PAINT GREEN (-3487 4408);
FORCEPROP 2 LAST CDS_LIB mstr_standard
J 0
(-3425 4400);
DISPLAY 0.723404 (-3425 4400);
PAINT MONO (-3425 4400);
DISPLAY INVISIBLE (-3425 4400);
FORCEPROP 1 LAST BODY_TYPE PLUMBING
J 0
(-3425 4450);
DISPLAY 0.872340 (-3425 4450);
PAINT GREEN (-3425 4450);
DISPLAY INVISIBLE (-3425 4450);
FORCEPROP 1 LAST HDL_TAP TRUE
J 0
(-3100 4275);
DISPLAY 0.872340 (-3100 4275);
DISPLAY INVISIBLE (-3100 4275);
FORCEPROP 1 LAST PATH I200
J 0
(-3427 4400);
DISPLAY 0.872340 (-3427 4400);
PAINT GREEN (-3427 4400);
DISPLAY INVISIBLE (-3427 4400);
FORCEADD TAP..1
(-3425 4350);
FORCEPROP 3 LASTPIN (-3475 4350) SIG_NAME M_G_CPU1_SA_DQ<31>
J 0
(-3465 4360);
DISPLAY 0.659574 (-3465 4360);
PAINT MONO (-3465 4360);
DISPLAY INVISIBLE (-3465 4360);
FORCEPROP 1 LASTPIN (-3475 4350) BN 31
J 0
(-3487 4358);
DISPLAY 0.489362 (-3487 4358);
PAINT GREEN (-3487 4358);
FORCEPROP 2 LAST CDS_LIB mstr_standard
J 0
(-3425 4350);
DISPLAY 0.723404 (-3425 4350);
PAINT MONO (-3425 4350);
DISPLAY INVISIBLE (-3425 4350);
FORCEPROP 1 LAST BODY_TYPE PLUMBING
J 0
(-3425 4400);
DISPLAY 0.872340 (-3425 4400);
PAINT GREEN (-3425 4400);
DISPLAY INVISIBLE (-3425 4400);
FORCEPROP 1 LAST HDL_TAP TRUE
J 0
(-3100 4225);
DISPLAY 0.872340 (-3100 4225);
DISPLAY INVISIBLE (-3100 4225);
FORCEPROP 1 LAST PATH I201
J 0
(-3427 4350);
DISPLAY 0.872340 (-3427 4350);
PAINT GREEN (-3427 4350);
DISPLAY INVISIBLE (-3427 4350);
FORCEADD TAP..1
(-3425 4250);
FORCEPROP 3 LASTPIN (-3475 4250) SIG_NAME M_G_CPU1_SB_DQ<0>
J 0
(-3465 4260);
DISPLAY 0.659574 (-3465 4260);
PAINT MONO (-3465 4260);
DISPLAY INVISIBLE (-3465 4260);
FORCEPROP 1 LASTPIN (-3475 4250) BN 0
J 0
(-3487 4258);
DISPLAY 0.489362 (-3487 4258);
PAINT GREEN (-3487 4258);
FORCEPROP 2 LAST CDS_LIB mstr_standard
J 0
(-3425 4250);
DISPLAY 0.723404 (-3425 4250);
PAINT MONO (-3425 4250);
DISPLAY INVISIBLE (-3425 4250);
FORCEPROP 1 LAST BODY_TYPE PLUMBING
J 0
(-3425 4300);
DISPLAY 0.872340 (-3425 4300);
PAINT GREEN (-3425 4300);
DISPLAY INVISIBLE (-3425 4300);
FORCEPROP 1 LAST HDL_TAP TRUE
J 0
(-3100 4125);
DISPLAY 0.872340 (-3100 4125);
DISPLAY INVISIBLE (-3100 4125);
FORCEPROP 1 LAST PATH I202
J 0
(-3427 4250);
DISPLAY 0.872340 (-3427 4250);
PAINT GREEN (-3427 4250);
DISPLAY INVISIBLE (-3427 4250);
FORCEADD TAP..1
(-3425 4200);
FORCEPROP 3 LASTPIN (-3475 4200) SIG_NAME M_G_CPU1_SB_DQ<1>
J 0
(-3465 4210);
DISPLAY 0.659574 (-3465 4210);
PAINT MONO (-3465 4210);
DISPLAY INVISIBLE (-3465 4210);
FORCEPROP 1 LASTPIN (-3475 4200) BN 1
J 0
(-3487 4208);
DISPLAY 0.489362 (-3487 4208);
PAINT GREEN (-3487 4208);
FORCEPROP 2 LAST CDS_LIB mstr_standard
J 0
(-3425 4200);
DISPLAY 0.723404 (-3425 4200);
PAINT MONO (-3425 4200);
DISPLAY INVISIBLE (-3425 4200);
FORCEPROP 1 LAST BODY_TYPE PLUMBING
J 0
(-3425 4250);
DISPLAY 0.872340 (-3425 4250);
PAINT GREEN (-3425 4250);
DISPLAY INVISIBLE (-3425 4250);
FORCEPROP 1 LAST HDL_TAP TRUE
J 0
(-3100 4075);
DISPLAY 0.872340 (-3100 4075);
DISPLAY INVISIBLE (-3100 4075);
FORCEPROP 1 LAST PATH I203
J 0
(-3427 4200);
DISPLAY 0.872340 (-3427 4200);
PAINT GREEN (-3427 4200);
DISPLAY INVISIBLE (-3427 4200);
FORCEADD TAP..1
(-3425 4100);
FORCEPROP 3 LASTPIN (-3475 4100) SIG_NAME M_G_CPU1_SB_DQ<3>
J 0
(-3465 4110);
DISPLAY 0.659574 (-3465 4110);
PAINT MONO (-3465 4110);
DISPLAY INVISIBLE (-3465 4110);
FORCEPROP 1 LASTPIN (-3475 4100) BN 3
J 0
(-3487 4108);
DISPLAY 0.489362 (-3487 4108);
PAINT GREEN (-3487 4108);
FORCEPROP 2 LAST CDS_LIB mstr_standard
J 0
(-3425 4100);
DISPLAY 0.723404 (-3425 4100);
PAINT MONO (-3425 4100);
DISPLAY INVISIBLE (-3425 4100);
FORCEPROP 1 LAST BODY_TYPE PLUMBING
J 0
(-3425 4150);
DISPLAY 0.872340 (-3425 4150);
PAINT GREEN (-3425 4150);
DISPLAY INVISIBLE (-3425 4150);
FORCEPROP 1 LAST HDL_TAP TRUE
J 0
(-3100 3975);
DISPLAY 0.872340 (-3100 3975);
DISPLAY INVISIBLE (-3100 3975);
FORCEPROP 1 LAST PATH I204
J 0
(-3427 4100);
DISPLAY 0.872340 (-3427 4100);
PAINT GREEN (-3427 4100);
DISPLAY INVISIBLE (-3427 4100);
FORCEADD TAP..1
(-3425 4150);
FORCEPROP 3 LASTPIN (-3475 4150) SIG_NAME M_G_CPU1_SB_DQ<2>
J 0
(-3465 4160);
DISPLAY 0.659574 (-3465 4160);
PAINT MONO (-3465 4160);
DISPLAY INVISIBLE (-3465 4160);
FORCEPROP 1 LASTPIN (-3475 4150) BN 2
J 0
(-3487 4158);
DISPLAY 0.489362 (-3487 4158);
PAINT GREEN (-3487 4158);
FORCEPROP 2 LAST CDS_LIB mstr_standard
J 0
(-3425 4150);
DISPLAY 0.723404 (-3425 4150);
PAINT MONO (-3425 4150);
DISPLAY INVISIBLE (-3425 4150);
FORCEPROP 1 LAST BODY_TYPE PLUMBING
J 0
(-3425 4200);
DISPLAY 0.872340 (-3425 4200);
PAINT GREEN (-3425 4200);
DISPLAY INVISIBLE (-3425 4200);
FORCEPROP 1 LAST HDL_TAP TRUE
J 0
(-3100 4025);
DISPLAY 0.872340 (-3100 4025);
DISPLAY INVISIBLE (-3100 4025);
FORCEPROP 1 LAST PATH I205
J 0
(-3427 4150);
DISPLAY 0.872340 (-3427 4150);
PAINT GREEN (-3427 4150);
DISPLAY INVISIBLE (-3427 4150);
FORCEADD OFFPAGE..6
R 2
(-2825 2500);
FORCEPROP 2 LAST $XR0 104 
J 0
(-2611 2500);
DISPLAY 0.638298 (-2611 2500);
PAINT MONO (-2611 2500);
FORCEPROP 2 LAST CDS_LIB mstr_standard
J 2
(-2825 2500);
DISPLAY 0.723404 (-2825 2500);
PAINT MONO (-2825 2500);
DISPLAY INVISIBLE (-2825 2500);
FORCEPROP 1 LAST OFFPAGE TRUE
J 2
(-3150 2375);
DISPLAY 0.872340 (-3150 2375);
PAINT GREEN (-3150 2375);
DISPLAY INVISIBLE (-3150 2375);
FORCEPROP 1 LAST COMMENT_BODY TRUE
J 2
(-2925 2425);
DISPLAY 0.872340 (-2925 2425);
PAINT GREEN (-2925 2425);
DISPLAY INVISIBLE (-2925 2425);
FORCEPROP 2 LAST PATH I206
J 0
(-2600 2550);
DISPLAY 1.021277 (-2600 2550);
DISPLAY INVISIBLE (-2600 2550);
FORCEADD TAP..1
(-3425 4050);
FORCEPROP 3 LASTPIN (-3475 4050) SIG_NAME M_G_CPU1_SB_DQ<4>
J 0
(-3465 4060);
DISPLAY 0.659574 (-3465 4060);
PAINT MONO (-3465 4060);
DISPLAY INVISIBLE (-3465 4060);
FORCEPROP 1 LASTPIN (-3475 4050) BN 4
J 0
(-3487 4058);
DISPLAY 0.489362 (-3487 4058);
PAINT GREEN (-3487 4058);
FORCEPROP 2 LAST CDS_LIB mstr_standard
J 0
(-3425 4050);
DISPLAY 0.723404 (-3425 4050);
PAINT MONO (-3425 4050);
DISPLAY INVISIBLE (-3425 4050);
FORCEPROP 1 LAST BODY_TYPE PLUMBING
J 0
(-3425 4100);
DISPLAY 0.872340 (-3425 4100);
PAINT GREEN (-3425 4100);
DISPLAY INVISIBLE (-3425 4100);
FORCEPROP 1 LAST HDL_TAP TRUE
J 0
(-3100 3925);
DISPLAY 0.872340 (-3100 3925);
DISPLAY INVISIBLE (-3100 3925);
FORCEPROP 1 LAST PATH I207
J 0
(-3427 4050);
DISPLAY 0.872340 (-3427 4050);
PAINT GREEN (-3427 4050);
DISPLAY INVISIBLE (-3427 4050);
FORCEADD TAP..1
(-3425 4000);
FORCEPROP 3 LASTPIN (-3475 4000) SIG_NAME M_G_CPU1_SB_DQ<5>
J 0
(-3465 4010);
DISPLAY 0.659574 (-3465 4010);
PAINT MONO (-3465 4010);
DISPLAY INVISIBLE (-3465 4010);
FORCEPROP 1 LASTPIN (-3475 4000) BN 5
J 0
(-3487 4008);
DISPLAY 0.489362 (-3487 4008);
PAINT GREEN (-3487 4008);
FORCEPROP 2 LAST CDS_LIB mstr_standard
J 0
(-3425 4000);
DISPLAY 0.723404 (-3425 4000);
PAINT MONO (-3425 4000);
DISPLAY INVISIBLE (-3425 4000);
FORCEPROP 1 LAST BODY_TYPE PLUMBING
J 0
(-3425 4050);
DISPLAY 0.872340 (-3425 4050);
PAINT GREEN (-3425 4050);
DISPLAY INVISIBLE (-3425 4050);
FORCEPROP 1 LAST HDL_TAP TRUE
J 0
(-3100 3875);
DISPLAY 0.872340 (-3100 3875);
DISPLAY INVISIBLE (-3100 3875);
FORCEPROP 1 LAST PATH I208
J 0
(-3427 4000);
DISPLAY 0.872340 (-3427 4000);
PAINT GREEN (-3427 4000);
DISPLAY INVISIBLE (-3427 4000);
FORCEADD TAP..1
(-3425 3950);
FORCEPROP 3 LASTPIN (-3475 3950) SIG_NAME M_G_CPU1_SB_DQ<6>
J 0
(-3465 3960);
DISPLAY 0.659574 (-3465 3960);
PAINT MONO (-3465 3960);
DISPLAY INVISIBLE (-3465 3960);
FORCEPROP 1 LASTPIN (-3475 3950) BN 6
J 0
(-3487 3958);
DISPLAY 0.489362 (-3487 3958);
PAINT GREEN (-3487 3958);
FORCEPROP 2 LAST CDS_LIB mstr_standard
J 0
(-3425 3950);
DISPLAY 0.723404 (-3425 3950);
PAINT MONO (-3425 3950);
DISPLAY INVISIBLE (-3425 3950);
FORCEPROP 1 LAST BODY_TYPE PLUMBING
J 0
(-3425 4000);
DISPLAY 0.872340 (-3425 4000);
PAINT GREEN (-3425 4000);
DISPLAY INVISIBLE (-3425 4000);
FORCEPROP 1 LAST HDL_TAP TRUE
J 0
(-3100 3825);
DISPLAY 0.872340 (-3100 3825);
DISPLAY INVISIBLE (-3100 3825);
FORCEPROP 1 LAST PATH I209
J 0
(-3427 3950);
DISPLAY 0.872340 (-3427 3950);
PAINT GREEN (-3427 3950);
DISPLAY INVISIBLE (-3427 3950);
FORCEADD TAP..1
(-3425 3900);
FORCEPROP 3 LASTPIN (-3475 3900) SIG_NAME M_G_CPU1_SB_DQ<7>
J 0
(-3465 3910);
DISPLAY 0.659574 (-3465 3910);
PAINT MONO (-3465 3910);
DISPLAY INVISIBLE (-3465 3910);
FORCEPROP 1 LASTPIN (-3475 3900) BN 7
J 0
(-3487 3908);
DISPLAY 0.489362 (-3487 3908);
PAINT GREEN (-3487 3908);
FORCEPROP 2 LAST CDS_LIB mstr_standard
J 0
(-3425 3900);
DISPLAY 0.723404 (-3425 3900);
PAINT MONO (-3425 3900);
DISPLAY INVISIBLE (-3425 3900);
FORCEPROP 1 LAST BODY_TYPE PLUMBING
J 0
(-3425 3950);
DISPLAY 0.872340 (-3425 3950);
PAINT GREEN (-3425 3950);
DISPLAY INVISIBLE (-3425 3950);
FORCEPROP 1 LAST HDL_TAP TRUE
J 0
(-3100 3775);
DISPLAY 0.872340 (-3100 3775);
DISPLAY INVISIBLE (-3100 3775);
FORCEPROP 1 LAST PATH I210
J 0
(-3427 3900);
DISPLAY 0.872340 (-3427 3900);
PAINT GREEN (-3427 3900);
DISPLAY INVISIBLE (-3427 3900);
FORCEADD TAP..1
(-3425 3800);
FORCEPROP 3 LASTPIN (-3475 3800) SIG_NAME M_G_CPU1_SB_DQ<8>
J 0
(-3465 3810);
DISPLAY 0.659574 (-3465 3810);
PAINT MONO (-3465 3810);
DISPLAY INVISIBLE (-3465 3810);
FORCEPROP 1 LASTPIN (-3475 3800) BN 8
J 0
(-3487 3808);
DISPLAY 0.489362 (-3487 3808);
PAINT GREEN (-3487 3808);
FORCEPROP 2 LAST CDS_LIB mstr_standard
J 0
(-3425 3800);
DISPLAY 0.723404 (-3425 3800);
PAINT MONO (-3425 3800);
DISPLAY INVISIBLE (-3425 3800);
FORCEPROP 1 LAST BODY_TYPE PLUMBING
J 0
(-3425 3850);
DISPLAY 0.872340 (-3425 3850);
PAINT GREEN (-3425 3850);
DISPLAY INVISIBLE (-3425 3850);
FORCEPROP 1 LAST HDL_TAP TRUE
J 0
(-3100 3675);
DISPLAY 0.872340 (-3100 3675);
DISPLAY INVISIBLE (-3100 3675);
FORCEPROP 1 LAST PATH I211
J 0
(-3427 3800);
DISPLAY 0.872340 (-3427 3800);
PAINT GREEN (-3427 3800);
DISPLAY INVISIBLE (-3427 3800);
FORCEADD TAP..1
(-3425 3750);
FORCEPROP 3 LASTPIN (-3475 3750) SIG_NAME M_G_CPU1_SB_DQ<9>
J 0
(-3465 3760);
DISPLAY 0.659574 (-3465 3760);
PAINT MONO (-3465 3760);
DISPLAY INVISIBLE (-3465 3760);
FORCEPROP 1 LASTPIN (-3475 3750) BN 9
J 0
(-3487 3758);
DISPLAY 0.489362 (-3487 3758);
PAINT GREEN (-3487 3758);
FORCEPROP 2 LAST CDS_LIB mstr_standard
J 0
(-3425 3750);
DISPLAY 0.723404 (-3425 3750);
PAINT MONO (-3425 3750);
DISPLAY INVISIBLE (-3425 3750);
FORCEPROP 1 LAST BODY_TYPE PLUMBING
J 0
(-3425 3800);
DISPLAY 0.872340 (-3425 3800);
PAINT GREEN (-3425 3800);
DISPLAY INVISIBLE (-3425 3800);
FORCEPROP 1 LAST HDL_TAP TRUE
J 0
(-3100 3625);
DISPLAY 0.872340 (-3100 3625);
DISPLAY INVISIBLE (-3100 3625);
FORCEPROP 1 LAST PATH I212
J 0
(-3427 3750);
DISPLAY 0.872340 (-3427 3750);
PAINT GREEN (-3427 3750);
DISPLAY INVISIBLE (-3427 3750);
FORCEADD TAP..1
(-3425 3700);
FORCEPROP 3 LASTPIN (-3475 3700) SIG_NAME M_G_CPU1_SB_DQ<10>
J 0
(-3465 3710);
DISPLAY 0.659574 (-3465 3710);
PAINT MONO (-3465 3710);
DISPLAY INVISIBLE (-3465 3710);
FORCEPROP 1 LASTPIN (-3475 3700) BN 10
J 0
(-3487 3708);
DISPLAY 0.489362 (-3487 3708);
PAINT GREEN (-3487 3708);
FORCEPROP 2 LAST CDS_LIB mstr_standard
J 0
(-3425 3700);
DISPLAY 0.723404 (-3425 3700);
PAINT MONO (-3425 3700);
DISPLAY INVISIBLE (-3425 3700);
FORCEPROP 1 LAST BODY_TYPE PLUMBING
J 0
(-3425 3750);
DISPLAY 0.872340 (-3425 3750);
PAINT GREEN (-3425 3750);
DISPLAY INVISIBLE (-3425 3750);
FORCEPROP 1 LAST HDL_TAP TRUE
J 0
(-3100 3575);
DISPLAY 0.872340 (-3100 3575);
DISPLAY INVISIBLE (-3100 3575);
FORCEPROP 1 LAST PATH I213
J 0
(-3427 3700);
DISPLAY 0.872340 (-3427 3700);
PAINT GREEN (-3427 3700);
DISPLAY INVISIBLE (-3427 3700);
FORCEADD TAP..1
(-3425 3650);
FORCEPROP 3 LASTPIN (-3475 3650) SIG_NAME M_G_CPU1_SB_DQ<11>
J 0
(-3465 3660);
DISPLAY 0.659574 (-3465 3660);
PAINT MONO (-3465 3660);
DISPLAY INVISIBLE (-3465 3660);
FORCEPROP 1 LASTPIN (-3475 3650) BN 11
J 0
(-3487 3658);
DISPLAY 0.489362 (-3487 3658);
PAINT GREEN (-3487 3658);
FORCEPROP 2 LAST CDS_LIB mstr_standard
J 0
(-3425 3650);
DISPLAY 0.723404 (-3425 3650);
PAINT MONO (-3425 3650);
DISPLAY INVISIBLE (-3425 3650);
FORCEPROP 1 LAST BODY_TYPE PLUMBING
J 0
(-3425 3700);
DISPLAY 0.872340 (-3425 3700);
PAINT GREEN (-3425 3700);
DISPLAY INVISIBLE (-3425 3700);
FORCEPROP 1 LAST HDL_TAP TRUE
J 0
(-3100 3525);
DISPLAY 0.872340 (-3100 3525);
DISPLAY INVISIBLE (-3100 3525);
FORCEPROP 1 LAST PATH I214
J 0
(-3427 3650);
DISPLAY 0.872340 (-3427 3650);
PAINT GREEN (-3427 3650);
DISPLAY INVISIBLE (-3427 3650);
FORCEADD TAP..1
(-3425 3600);
FORCEPROP 3 LASTPIN (-3475 3600) SIG_NAME M_G_CPU1_SB_DQ<12>
J 0
(-3465 3610);
DISPLAY 0.659574 (-3465 3610);
PAINT MONO (-3465 3610);
DISPLAY INVISIBLE (-3465 3610);
FORCEPROP 1 LASTPIN (-3475 3600) BN 12
J 0
(-3487 3608);
DISPLAY 0.489362 (-3487 3608);
PAINT GREEN (-3487 3608);
FORCEPROP 2 LAST CDS_LIB mstr_standard
J 0
(-3425 3600);
DISPLAY 0.723404 (-3425 3600);
PAINT MONO (-3425 3600);
DISPLAY INVISIBLE (-3425 3600);
FORCEPROP 1 LAST BODY_TYPE PLUMBING
J 0
(-3425 3650);
DISPLAY 0.872340 (-3425 3650);
PAINT GREEN (-3425 3650);
DISPLAY INVISIBLE (-3425 3650);
FORCEPROP 1 LAST HDL_TAP TRUE
J 0
(-3100 3475);
DISPLAY 0.872340 (-3100 3475);
DISPLAY INVISIBLE (-3100 3475);
FORCEPROP 1 LAST PATH I215
J 0
(-3427 3600);
DISPLAY 0.872340 (-3427 3600);
PAINT GREEN (-3427 3600);
DISPLAY INVISIBLE (-3427 3600);
FORCEADD TAP..1
(-3425 3550);
FORCEPROP 3 LASTPIN (-3475 3550) SIG_NAME M_G_CPU1_SB_DQ<13>
J 0
(-3465 3560);
DISPLAY 0.659574 (-3465 3560);
PAINT MONO (-3465 3560);
DISPLAY INVISIBLE (-3465 3560);
FORCEPROP 1 LASTPIN (-3475 3550) BN 13
J 0
(-3487 3558);
DISPLAY 0.489362 (-3487 3558);
PAINT GREEN (-3487 3558);
FORCEPROP 2 LAST CDS_LIB mstr_standard
J 0
(-3425 3550);
DISPLAY 0.723404 (-3425 3550);
PAINT MONO (-3425 3550);
DISPLAY INVISIBLE (-3425 3550);
FORCEPROP 1 LAST BODY_TYPE PLUMBING
J 0
(-3425 3600);
DISPLAY 0.872340 (-3425 3600);
PAINT GREEN (-3425 3600);
DISPLAY INVISIBLE (-3425 3600);
FORCEPROP 1 LAST HDL_TAP TRUE
J 0
(-3100 3425);
DISPLAY 0.872340 (-3100 3425);
DISPLAY INVISIBLE (-3100 3425);
FORCEPROP 1 LAST PATH I216
J 0
(-3427 3550);
DISPLAY 0.872340 (-3427 3550);
PAINT GREEN (-3427 3550);
DISPLAY INVISIBLE (-3427 3550);
FORCEADD TAP..1
(-3425 3500);
FORCEPROP 3 LASTPIN (-3475 3500) SIG_NAME M_G_CPU1_SB_DQ<14>
J 0
(-3465 3510);
DISPLAY 0.659574 (-3465 3510);
PAINT MONO (-3465 3510);
DISPLAY INVISIBLE (-3465 3510);
FORCEPROP 1 LASTPIN (-3475 3500) BN 14
J 0
(-3487 3508);
DISPLAY 0.489362 (-3487 3508);
PAINT GREEN (-3487 3508);
FORCEPROP 2 LAST CDS_LIB mstr_standard
J 0
(-3425 3500);
DISPLAY 0.723404 (-3425 3500);
PAINT MONO (-3425 3500);
DISPLAY INVISIBLE (-3425 3500);
FORCEPROP 1 LAST BODY_TYPE PLUMBING
J 0
(-3425 3550);
DISPLAY 0.872340 (-3425 3550);
PAINT GREEN (-3425 3550);
DISPLAY INVISIBLE (-3425 3550);
FORCEPROP 1 LAST HDL_TAP TRUE
J 0
(-3100 3375);
DISPLAY 0.872340 (-3100 3375);
DISPLAY INVISIBLE (-3100 3375);
FORCEPROP 1 LAST PATH I217
J 0
(-3427 3500);
DISPLAY 0.872340 (-3427 3500);
PAINT GREEN (-3427 3500);
DISPLAY INVISIBLE (-3427 3500);
FORCEADD TAP..1
(-3425 3450);
FORCEPROP 3 LASTPIN (-3475 3450) SIG_NAME M_G_CPU1_SB_DQ<15>
J 0
(-3465 3460);
DISPLAY 0.659574 (-3465 3460);
PAINT MONO (-3465 3460);
DISPLAY INVISIBLE (-3465 3460);
FORCEPROP 1 LASTPIN (-3475 3450) BN 15
J 0
(-3487 3458);
DISPLAY 0.489362 (-3487 3458);
PAINT GREEN (-3487 3458);
FORCEPROP 2 LAST CDS_LIB mstr_standard
J 0
(-3425 3450);
DISPLAY 0.723404 (-3425 3450);
PAINT MONO (-3425 3450);
DISPLAY INVISIBLE (-3425 3450);
FORCEPROP 1 LAST BODY_TYPE PLUMBING
J 0
(-3425 3500);
DISPLAY 0.872340 (-3425 3500);
PAINT GREEN (-3425 3500);
DISPLAY INVISIBLE (-3425 3500);
FORCEPROP 1 LAST HDL_TAP TRUE
J 0
(-3100 3325);
DISPLAY 0.872340 (-3100 3325);
DISPLAY INVISIBLE (-3100 3325);
FORCEPROP 1 LAST PATH I218
J 0
(-3427 3450);
DISPLAY 0.872340 (-3427 3450);
PAINT GREEN (-3427 3450);
DISPLAY INVISIBLE (-3427 3450);
FORCEADD TAP..1
(-3425 3350);
FORCEPROP 3 LASTPIN (-3475 3350) SIG_NAME M_G_CPU1_SB_DQ<16>
J 0
(-3465 3360);
DISPLAY 0.659574 (-3465 3360);
PAINT MONO (-3465 3360);
DISPLAY INVISIBLE (-3465 3360);
FORCEPROP 1 LASTPIN (-3475 3350) BN 16
J 0
(-3487 3358);
DISPLAY 0.489362 (-3487 3358);
PAINT GREEN (-3487 3358);
FORCEPROP 2 LAST CDS_LIB mstr_standard
J 0
(-3425 3350);
DISPLAY 0.723404 (-3425 3350);
PAINT MONO (-3425 3350);
DISPLAY INVISIBLE (-3425 3350);
FORCEPROP 1 LAST BODY_TYPE PLUMBING
J 0
(-3425 3400);
DISPLAY 0.872340 (-3425 3400);
PAINT GREEN (-3425 3400);
DISPLAY INVISIBLE (-3425 3400);
FORCEPROP 1 LAST HDL_TAP TRUE
J 0
(-3100 3225);
DISPLAY 0.872340 (-3100 3225);
DISPLAY INVISIBLE (-3100 3225);
FORCEPROP 1 LAST PATH I219
J 0
(-3427 3350);
DISPLAY 0.872340 (-3427 3350);
PAINT GREEN (-3427 3350);
DISPLAY INVISIBLE (-3427 3350);
FORCEADD TAP..1
(-3425 3300);
FORCEPROP 3 LASTPIN (-3475 3300) SIG_NAME M_G_CPU1_SB_DQ<17>
J 0
(-3465 3310);
DISPLAY 0.659574 (-3465 3310);
PAINT MONO (-3465 3310);
DISPLAY INVISIBLE (-3465 3310);
FORCEPROP 1 LASTPIN (-3475 3300) BN 17
J 0
(-3487 3308);
DISPLAY 0.489362 (-3487 3308);
PAINT GREEN (-3487 3308);
FORCEPROP 2 LAST CDS_LIB mstr_standard
J 0
(-3425 3300);
DISPLAY 0.723404 (-3425 3300);
PAINT MONO (-3425 3300);
DISPLAY INVISIBLE (-3425 3300);
FORCEPROP 1 LAST BODY_TYPE PLUMBING
J 0
(-3425 3350);
DISPLAY 0.872340 (-3425 3350);
PAINT GREEN (-3425 3350);
DISPLAY INVISIBLE (-3425 3350);
FORCEPROP 1 LAST HDL_TAP TRUE
J 0
(-3100 3175);
DISPLAY 0.872340 (-3100 3175);
DISPLAY INVISIBLE (-3100 3175);
FORCEPROP 1 LAST PATH I220
J 0
(-3427 3300);
DISPLAY 0.872340 (-3427 3300);
PAINT GREEN (-3427 3300);
DISPLAY INVISIBLE (-3427 3300);
FORCEADD TAP..1
(-3425 3250);
FORCEPROP 3 LASTPIN (-3475 3250) SIG_NAME M_G_CPU1_SB_DQ<18>
J 0
(-3465 3260);
DISPLAY 0.659574 (-3465 3260);
PAINT MONO (-3465 3260);
DISPLAY INVISIBLE (-3465 3260);
FORCEPROP 1 LASTPIN (-3475 3250) BN 18
J 0
(-3487 3258);
DISPLAY 0.489362 (-3487 3258);
PAINT GREEN (-3487 3258);
FORCEPROP 2 LAST CDS_LIB mstr_standard
J 0
(-3425 3250);
DISPLAY 0.723404 (-3425 3250);
PAINT MONO (-3425 3250);
DISPLAY INVISIBLE (-3425 3250);
FORCEPROP 1 LAST BODY_TYPE PLUMBING
J 0
(-3425 3300);
DISPLAY 0.872340 (-3425 3300);
PAINT GREEN (-3425 3300);
DISPLAY INVISIBLE (-3425 3300);
FORCEPROP 1 LAST HDL_TAP TRUE
J 0
(-3100 3125);
DISPLAY 0.872340 (-3100 3125);
DISPLAY INVISIBLE (-3100 3125);
FORCEPROP 1 LAST PATH I221
J 0
(-3427 3250);
DISPLAY 0.872340 (-3427 3250);
PAINT GREEN (-3427 3250);
DISPLAY INVISIBLE (-3427 3250);
FORCEADD TAP..1
(-3425 3200);
FORCEPROP 3 LASTPIN (-3475 3200) SIG_NAME M_G_CPU1_SB_DQ<19>
J 0
(-3465 3210);
DISPLAY 0.659574 (-3465 3210);
PAINT MONO (-3465 3210);
DISPLAY INVISIBLE (-3465 3210);
FORCEPROP 1 LASTPIN (-3475 3200) BN 19
J 0
(-3487 3208);
DISPLAY 0.489362 (-3487 3208);
PAINT GREEN (-3487 3208);
FORCEPROP 2 LAST CDS_LIB mstr_standard
J 0
(-3425 3200);
DISPLAY 0.723404 (-3425 3200);
PAINT MONO (-3425 3200);
DISPLAY INVISIBLE (-3425 3200);
FORCEPROP 1 LAST BODY_TYPE PLUMBING
J 0
(-3425 3250);
DISPLAY 0.872340 (-3425 3250);
PAINT GREEN (-3425 3250);
DISPLAY INVISIBLE (-3425 3250);
FORCEPROP 1 LAST HDL_TAP TRUE
J 0
(-3100 3075);
DISPLAY 0.872340 (-3100 3075);
DISPLAY INVISIBLE (-3100 3075);
FORCEPROP 1 LAST PATH I222
J 0
(-3427 3200);
DISPLAY 0.872340 (-3427 3200);
PAINT GREEN (-3427 3200);
DISPLAY INVISIBLE (-3427 3200);
FORCEADD TAP..1
(-3425 3150);
FORCEPROP 3 LASTPIN (-3475 3150) SIG_NAME M_G_CPU1_SB_DQ<20>
J 0
(-3465 3160);
DISPLAY 0.659574 (-3465 3160);
PAINT MONO (-3465 3160);
DISPLAY INVISIBLE (-3465 3160);
FORCEPROP 1 LASTPIN (-3475 3150) BN 20
J 0
(-3487 3158);
DISPLAY 0.489362 (-3487 3158);
PAINT GREEN (-3487 3158);
FORCEPROP 2 LAST CDS_LIB mstr_standard
J 0
(-3425 3150);
DISPLAY 0.723404 (-3425 3150);
PAINT MONO (-3425 3150);
DISPLAY INVISIBLE (-3425 3150);
FORCEPROP 1 LAST BODY_TYPE PLUMBING
J 0
(-3425 3200);
DISPLAY 0.872340 (-3425 3200);
PAINT GREEN (-3425 3200);
DISPLAY INVISIBLE (-3425 3200);
FORCEPROP 1 LAST HDL_TAP TRUE
J 0
(-3100 3025);
DISPLAY 0.872340 (-3100 3025);
DISPLAY INVISIBLE (-3100 3025);
FORCEPROP 1 LAST PATH I223
J 0
(-3427 3150);
DISPLAY 0.872340 (-3427 3150);
PAINT GREEN (-3427 3150);
DISPLAY INVISIBLE (-3427 3150);
FORCEADD TAP..1
(-3425 3100);
FORCEPROP 3 LASTPIN (-3475 3100) SIG_NAME M_G_CPU1_SB_DQ<21>
J 0
(-3465 3110);
DISPLAY 0.659574 (-3465 3110);
PAINT MONO (-3465 3110);
DISPLAY INVISIBLE (-3465 3110);
FORCEPROP 1 LASTPIN (-3475 3100) BN 21
J 0
(-3487 3108);
DISPLAY 0.489362 (-3487 3108);
PAINT GREEN (-3487 3108);
FORCEPROP 2 LAST CDS_LIB mstr_standard
J 0
(-3425 3100);
DISPLAY 0.723404 (-3425 3100);
PAINT MONO (-3425 3100);
DISPLAY INVISIBLE (-3425 3100);
FORCEPROP 1 LAST BODY_TYPE PLUMBING
J 0
(-3425 3150);
DISPLAY 0.872340 (-3425 3150);
PAINT GREEN (-3425 3150);
DISPLAY INVISIBLE (-3425 3150);
FORCEPROP 1 LAST HDL_TAP TRUE
J 0
(-3100 2975);
DISPLAY 0.872340 (-3100 2975);
DISPLAY INVISIBLE (-3100 2975);
FORCEPROP 1 LAST PATH I224
J 0
(-3427 3100);
DISPLAY 0.872340 (-3427 3100);
PAINT GREEN (-3427 3100);
DISPLAY INVISIBLE (-3427 3100);
FORCEADD TAP..1
(-3425 3000);
FORCEPROP 3 LASTPIN (-3475 3000) SIG_NAME M_G_CPU1_SB_DQ<23>
J 0
(-3465 3010);
DISPLAY 0.659574 (-3465 3010);
PAINT MONO (-3465 3010);
DISPLAY INVISIBLE (-3465 3010);
FORCEPROP 1 LASTPIN (-3475 3000) BN 23
J 0
(-3487 3008);
DISPLAY 0.489362 (-3487 3008);
PAINT GREEN (-3487 3008);
FORCEPROP 2 LAST CDS_LIB mstr_standard
J 0
(-3425 3000);
DISPLAY 0.723404 (-3425 3000);
PAINT MONO (-3425 3000);
DISPLAY INVISIBLE (-3425 3000);
FORCEPROP 1 LAST BODY_TYPE PLUMBING
J 0
(-3425 3050);
DISPLAY 0.872340 (-3425 3050);
PAINT GREEN (-3425 3050);
DISPLAY INVISIBLE (-3425 3050);
FORCEPROP 1 LAST HDL_TAP TRUE
J 0
(-3100 2875);
DISPLAY 0.872340 (-3100 2875);
DISPLAY INVISIBLE (-3100 2875);
FORCEPROP 1 LAST PATH I225
J 0
(-3427 3000);
DISPLAY 0.872340 (-3427 3000);
PAINT GREEN (-3427 3000);
DISPLAY INVISIBLE (-3427 3000);
FORCEADD TAP..1
(-3425 3050);
FORCEPROP 3 LASTPIN (-3475 3050) SIG_NAME M_G_CPU1_SB_DQ<22>
J 0
(-3465 3060);
DISPLAY 0.659574 (-3465 3060);
PAINT MONO (-3465 3060);
DISPLAY INVISIBLE (-3465 3060);
FORCEPROP 1 LASTPIN (-3475 3050) BN 22
J 0
(-3487 3058);
DISPLAY 0.489362 (-3487 3058);
PAINT GREEN (-3487 3058);
FORCEPROP 2 LAST CDS_LIB mstr_standard
J 0
(-3425 3050);
DISPLAY 0.723404 (-3425 3050);
PAINT MONO (-3425 3050);
DISPLAY INVISIBLE (-3425 3050);
FORCEPROP 1 LAST BODY_TYPE PLUMBING
J 0
(-3425 3100);
DISPLAY 0.872340 (-3425 3100);
PAINT GREEN (-3425 3100);
DISPLAY INVISIBLE (-3425 3100);
FORCEPROP 1 LAST HDL_TAP TRUE
J 0
(-3100 2925);
DISPLAY 0.872340 (-3100 2925);
DISPLAY INVISIBLE (-3100 2925);
FORCEPROP 1 LAST PATH I226
J 0
(-3427 3050);
DISPLAY 0.872340 (-3427 3050);
PAINT GREEN (-3427 3050);
DISPLAY INVISIBLE (-3427 3050);
FORCEADD TAP..1
(-3425 2900);
FORCEPROP 3 LASTPIN (-3475 2900) SIG_NAME M_G_CPU1_SB_DQ<24>
J 0
(-3465 2910);
DISPLAY 0.659574 (-3465 2910);
PAINT MONO (-3465 2910);
DISPLAY INVISIBLE (-3465 2910);
FORCEPROP 1 LASTPIN (-3475 2900) BN 24
J 0
(-3487 2908);
DISPLAY 0.489362 (-3487 2908);
PAINT GREEN (-3487 2908);
FORCEPROP 2 LAST CDS_LIB mstr_standard
J 0
(-3425 2900);
DISPLAY 0.723404 (-3425 2900);
PAINT MONO (-3425 2900);
DISPLAY INVISIBLE (-3425 2900);
FORCEPROP 1 LAST BODY_TYPE PLUMBING
J 0
(-3425 2950);
DISPLAY 0.872340 (-3425 2950);
PAINT GREEN (-3425 2950);
DISPLAY INVISIBLE (-3425 2950);
FORCEPROP 1 LAST HDL_TAP TRUE
J 0
(-3100 2775);
DISPLAY 0.872340 (-3100 2775);
DISPLAY INVISIBLE (-3100 2775);
FORCEPROP 1 LAST PATH I227
J 0
(-3427 2900);
DISPLAY 0.872340 (-3427 2900);
PAINT GREEN (-3427 2900);
DISPLAY INVISIBLE (-3427 2900);
FORCEADD TAP..1
(-3425 2850);
FORCEPROP 3 LASTPIN (-3475 2850) SIG_NAME M_G_CPU1_SB_DQ<25>
J 0
(-3465 2860);
DISPLAY 0.659574 (-3465 2860);
PAINT MONO (-3465 2860);
DISPLAY INVISIBLE (-3465 2860);
FORCEPROP 1 LASTPIN (-3475 2850) BN 25
J 0
(-3487 2858);
DISPLAY 0.489362 (-3487 2858);
PAINT GREEN (-3487 2858);
FORCEPROP 2 LAST CDS_LIB mstr_standard
J 0
(-3425 2850);
DISPLAY 0.723404 (-3425 2850);
PAINT MONO (-3425 2850);
DISPLAY INVISIBLE (-3425 2850);
FORCEPROP 1 LAST BODY_TYPE PLUMBING
J 0
(-3425 2900);
DISPLAY 0.872340 (-3425 2900);
PAINT GREEN (-3425 2900);
DISPLAY INVISIBLE (-3425 2900);
FORCEPROP 1 LAST HDL_TAP TRUE
J 0
(-3100 2725);
DISPLAY 0.872340 (-3100 2725);
DISPLAY INVISIBLE (-3100 2725);
FORCEPROP 1 LAST PATH I228
J 0
(-3427 2850);
DISPLAY 0.872340 (-3427 2850);
PAINT GREEN (-3427 2850);
DISPLAY INVISIBLE (-3427 2850);
FORCEADD TAP..1
(-3425 2800);
FORCEPROP 3 LASTPIN (-3475 2800) SIG_NAME M_G_CPU1_SB_DQ<26>
J 0
(-3465 2810);
DISPLAY 0.659574 (-3465 2810);
PAINT MONO (-3465 2810);
DISPLAY INVISIBLE (-3465 2810);
FORCEPROP 1 LASTPIN (-3475 2800) BN 26
J 0
(-3487 2808);
DISPLAY 0.489362 (-3487 2808);
PAINT GREEN (-3487 2808);
FORCEPROP 2 LAST CDS_LIB mstr_standard
J 0
(-3425 2800);
DISPLAY 0.723404 (-3425 2800);
PAINT MONO (-3425 2800);
DISPLAY INVISIBLE (-3425 2800);
FORCEPROP 1 LAST BODY_TYPE PLUMBING
J 0
(-3425 2850);
DISPLAY 0.872340 (-3425 2850);
PAINT GREEN (-3425 2850);
DISPLAY INVISIBLE (-3425 2850);
FORCEPROP 1 LAST HDL_TAP TRUE
J 0
(-3100 2675);
DISPLAY 0.872340 (-3100 2675);
DISPLAY INVISIBLE (-3100 2675);
FORCEPROP 1 LAST PATH I229
J 0
(-3427 2800);
DISPLAY 0.872340 (-3427 2800);
PAINT GREEN (-3427 2800);
DISPLAY INVISIBLE (-3427 2800);
FORCEADD TAP..1
(-3425 2700);
FORCEPROP 3 LASTPIN (-3475 2700) SIG_NAME M_G_CPU1_SB_DQ<28>
J 0
(-3465 2710);
DISPLAY 0.659574 (-3465 2710);
PAINT MONO (-3465 2710);
DISPLAY INVISIBLE (-3465 2710);
FORCEPROP 1 LASTPIN (-3475 2700) BN 28
J 0
(-3487 2708);
DISPLAY 0.489362 (-3487 2708);
PAINT GREEN (-3487 2708);
FORCEPROP 2 LAST CDS_LIB mstr_standard
J 0
(-3425 2700);
DISPLAY 0.723404 (-3425 2700);
PAINT MONO (-3425 2700);
DISPLAY INVISIBLE (-3425 2700);
FORCEPROP 1 LAST BODY_TYPE PLUMBING
J 0
(-3425 2750);
DISPLAY 0.872340 (-3425 2750);
PAINT GREEN (-3425 2750);
DISPLAY INVISIBLE (-3425 2750);
FORCEPROP 1 LAST HDL_TAP TRUE
J 0
(-3100 2575);
DISPLAY 0.872340 (-3100 2575);
DISPLAY INVISIBLE (-3100 2575);
FORCEPROP 1 LAST PATH I230
J 0
(-3427 2700);
DISPLAY 0.872340 (-3427 2700);
PAINT GREEN (-3427 2700);
DISPLAY INVISIBLE (-3427 2700);
FORCEADD TAP..1
(-3425 2750);
FORCEPROP 3 LASTPIN (-3475 2750) SIG_NAME M_G_CPU1_SB_DQ<27>
J 0
(-3465 2760);
DISPLAY 0.659574 (-3465 2760);
PAINT MONO (-3465 2760);
DISPLAY INVISIBLE (-3465 2760);
FORCEPROP 1 LASTPIN (-3475 2750) BN 27
J 0
(-3487 2758);
DISPLAY 0.489362 (-3487 2758);
PAINT GREEN (-3487 2758);
FORCEPROP 2 LAST CDS_LIB mstr_standard
J 0
(-3425 2750);
DISPLAY 0.723404 (-3425 2750);
PAINT MONO (-3425 2750);
DISPLAY INVISIBLE (-3425 2750);
FORCEPROP 1 LAST BODY_TYPE PLUMBING
J 0
(-3425 2800);
DISPLAY 0.872340 (-3425 2800);
PAINT GREEN (-3425 2800);
DISPLAY INVISIBLE (-3425 2800);
FORCEPROP 1 LAST HDL_TAP TRUE
J 0
(-3100 2625);
DISPLAY 0.872340 (-3100 2625);
DISPLAY INVISIBLE (-3100 2625);
FORCEPROP 1 LAST PATH I231
J 0
(-3427 2750);
DISPLAY 0.872340 (-3427 2750);
PAINT GREEN (-3427 2750);
DISPLAY INVISIBLE (-3427 2750);
FORCEADD TAP..1
(-3425 2650);
FORCEPROP 3 LASTPIN (-3475 2650) SIG_NAME M_G_CPU1_SB_DQ<29>
J 0
(-3465 2660);
DISPLAY 0.659574 (-3465 2660);
PAINT MONO (-3465 2660);
DISPLAY INVISIBLE (-3465 2660);
FORCEPROP 1 LASTPIN (-3475 2650) BN 29
J 0
(-3487 2658);
DISPLAY 0.489362 (-3487 2658);
PAINT GREEN (-3487 2658);
FORCEPROP 2 LAST CDS_LIB mstr_standard
J 0
(-3425 2650);
DISPLAY 0.723404 (-3425 2650);
PAINT MONO (-3425 2650);
DISPLAY INVISIBLE (-3425 2650);
FORCEPROP 1 LAST BODY_TYPE PLUMBING
J 0
(-3425 2700);
DISPLAY 0.872340 (-3425 2700);
PAINT GREEN (-3425 2700);
DISPLAY INVISIBLE (-3425 2700);
FORCEPROP 1 LAST HDL_TAP TRUE
J 0
(-3100 2525);
DISPLAY 0.872340 (-3100 2525);
DISPLAY INVISIBLE (-3100 2525);
FORCEPROP 1 LAST PATH I232
J 0
(-3427 2650);
DISPLAY 0.872340 (-3427 2650);
PAINT GREEN (-3427 2650);
DISPLAY INVISIBLE (-3427 2650);
FORCEADD TAP..1
(-3425 2600);
FORCEPROP 3 LASTPIN (-3475 2600) SIG_NAME M_G_CPU1_SB_DQ<30>
J 0
(-3465 2610);
DISPLAY 0.659574 (-3465 2610);
PAINT MONO (-3465 2610);
DISPLAY INVISIBLE (-3465 2610);
FORCEPROP 1 LASTPIN (-3475 2600) BN 30
J 0
(-3487 2608);
DISPLAY 0.489362 (-3487 2608);
PAINT GREEN (-3487 2608);
FORCEPROP 2 LAST CDS_LIB mstr_standard
J 0
(-3425 2600);
DISPLAY 0.723404 (-3425 2600);
PAINT MONO (-3425 2600);
DISPLAY INVISIBLE (-3425 2600);
FORCEPROP 1 LAST BODY_TYPE PLUMBING
J 0
(-3425 2650);
DISPLAY 0.872340 (-3425 2650);
PAINT GREEN (-3425 2650);
DISPLAY INVISIBLE (-3425 2650);
FORCEPROP 1 LAST HDL_TAP TRUE
J 0
(-3100 2475);
DISPLAY 0.872340 (-3100 2475);
DISPLAY INVISIBLE (-3100 2475);
FORCEPROP 1 LAST PATH I233
J 0
(-3427 2600);
DISPLAY 0.872340 (-3427 2600);
PAINT GREEN (-3427 2600);
DISPLAY INVISIBLE (-3427 2600);
FORCEADD TAP..1
(-3425 2550);
FORCEPROP 3 LASTPIN (-3475 2550) SIG_NAME M_G_CPU1_SB_DQ<31>
J 0
(-3465 2560);
DISPLAY 0.659574 (-3465 2560);
PAINT MONO (-3465 2560);
DISPLAY INVISIBLE (-3465 2560);
FORCEPROP 1 LASTPIN (-3475 2550) BN 31
J 0
(-3487 2558);
DISPLAY 0.489362 (-3487 2558);
PAINT GREEN (-3487 2558);
FORCEPROP 2 LAST CDS_LIB mstr_standard
J 0
(-3425 2550);
DISPLAY 0.723404 (-3425 2550);
PAINT MONO (-3425 2550);
DISPLAY INVISIBLE (-3425 2550);
FORCEPROP 1 LAST BODY_TYPE PLUMBING
J 0
(-3425 2600);
DISPLAY 0.872340 (-3425 2600);
PAINT GREEN (-3425 2600);
DISPLAY INVISIBLE (-3425 2600);
FORCEPROP 1 LAST HDL_TAP TRUE
J 0
(-3100 2425);
DISPLAY 0.872340 (-3100 2425);
DISPLAY INVISIBLE (-3100 2425);
FORCEPROP 1 LAST PATH I234
J 0
(-3427 2550);
DISPLAY 0.872340 (-3427 2550);
PAINT GREEN (-3427 2550);
DISPLAY INVISIBLE (-3427 2550);
FORCEADD TAP..1
(-3425 2450);
FORCEPROP 3 LASTPIN (-3475 2450) SIG_NAME M_G_CPU1_SA_CB<0>
J 0
(-3465 2460);
DISPLAY 0.659574 (-3465 2460);
PAINT MONO (-3465 2460);
DISPLAY INVISIBLE (-3465 2460);
FORCEPROP 1 LASTPIN (-3475 2450) BN 0
J 0
(-3487 2458);
DISPLAY 0.489362 (-3487 2458);
PAINT GREEN (-3487 2458);
FORCEPROP 2 LAST CDS_LIB mstr_standard
J 2
(-3425 2450);
DISPLAY 0.723404 (-3425 2450);
PAINT MONO (-3425 2450);
DISPLAY INVISIBLE (-3425 2450);
FORCEPROP 1 LAST BODY_TYPE PLUMBING
J 0
(-3425 2500);
DISPLAY 0.872340 (-3425 2500);
PAINT GREEN (-3425 2500);
DISPLAY INVISIBLE (-3425 2500);
FORCEPROP 1 LAST HDL_TAP TRUE
J 0
(-3100 2325);
DISPLAY 0.872340 (-3100 2325);
DISPLAY INVISIBLE (-3100 2325);
FORCEPROP 1 LAST PATH I235
J 0
(-3427 2450);
DISPLAY 0.872340 (-3427 2450);
PAINT GREEN (-3427 2450);
DISPLAY INVISIBLE (-3427 2450);
FORCEADD TAP..1
(-3425 2400);
FORCEPROP 3 LASTPIN (-3475 2400) SIG_NAME M_G_CPU1_SA_CB<1>
J 0
(-3465 2410);
DISPLAY 0.659574 (-3465 2410);
PAINT MONO (-3465 2410);
DISPLAY INVISIBLE (-3465 2410);
FORCEPROP 1 LASTPIN (-3475 2400) BN 1
J 0
(-3487 2408);
DISPLAY 0.489362 (-3487 2408);
PAINT GREEN (-3487 2408);
FORCEPROP 2 LAST CDS_LIB mstr_standard
J 2
(-3425 2400);
DISPLAY 0.723404 (-3425 2400);
PAINT MONO (-3425 2400);
DISPLAY INVISIBLE (-3425 2400);
FORCEPROP 1 LAST BODY_TYPE PLUMBING
J 0
(-3425 2450);
DISPLAY 0.872340 (-3425 2450);
PAINT GREEN (-3425 2450);
DISPLAY INVISIBLE (-3425 2450);
FORCEPROP 1 LAST HDL_TAP TRUE
J 0
(-3100 2275);
DISPLAY 0.872340 (-3100 2275);
DISPLAY INVISIBLE (-3100 2275);
FORCEPROP 1 LAST PATH I236
J 0
(-3427 2400);
DISPLAY 0.872340 (-3427 2400);
PAINT GREEN (-3427 2400);
DISPLAY INVISIBLE (-3427 2400);
FORCEADD TAP..1
(-3425 2350);
FORCEPROP 3 LASTPIN (-3475 2350) SIG_NAME M_G_CPU1_SA_CB<2>
J 0
(-3465 2360);
DISPLAY 0.659574 (-3465 2360);
PAINT MONO (-3465 2360);
DISPLAY INVISIBLE (-3465 2360);
FORCEPROP 1 LASTPIN (-3475 2350) BN 2
J 0
(-3487 2358);
DISPLAY 0.489362 (-3487 2358);
PAINT GREEN (-3487 2358);
FORCEPROP 2 LAST CDS_LIB mstr_standard
J 2
(-3425 2350);
DISPLAY 0.723404 (-3425 2350);
PAINT MONO (-3425 2350);
DISPLAY INVISIBLE (-3425 2350);
FORCEPROP 1 LAST BODY_TYPE PLUMBING
J 0
(-3425 2400);
DISPLAY 0.872340 (-3425 2400);
PAINT GREEN (-3425 2400);
DISPLAY INVISIBLE (-3425 2400);
FORCEPROP 1 LAST HDL_TAP TRUE
J 0
(-3100 2225);
DISPLAY 0.872340 (-3100 2225);
DISPLAY INVISIBLE (-3100 2225);
FORCEPROP 1 LAST PATH I237
J 0
(-3427 2350);
DISPLAY 0.872340 (-3427 2350);
PAINT GREEN (-3427 2350);
DISPLAY INVISIBLE (-3427 2350);
FORCEADD TAP..1
(-3425 2300);
FORCEPROP 3 LASTPIN (-3475 2300) SIG_NAME M_G_CPU1_SA_CB<3>
J 0
(-3465 2310);
DISPLAY 0.659574 (-3465 2310);
PAINT MONO (-3465 2310);
DISPLAY INVISIBLE (-3465 2310);
FORCEPROP 1 LASTPIN (-3475 2300) BN 3
J 0
(-3487 2308);
DISPLAY 0.489362 (-3487 2308);
PAINT GREEN (-3487 2308);
FORCEPROP 2 LAST CDS_LIB mstr_standard
J 2
(-3425 2300);
DISPLAY 0.723404 (-3425 2300);
PAINT MONO (-3425 2300);
DISPLAY INVISIBLE (-3425 2300);
FORCEPROP 1 LAST BODY_TYPE PLUMBING
J 0
(-3425 2350);
DISPLAY 0.872340 (-3425 2350);
PAINT GREEN (-3425 2350);
DISPLAY INVISIBLE (-3425 2350);
FORCEPROP 1 LAST HDL_TAP TRUE
J 0
(-3100 2175);
DISPLAY 0.872340 (-3100 2175);
DISPLAY INVISIBLE (-3100 2175);
FORCEPROP 1 LAST PATH I238
J 0
(-3427 2300);
DISPLAY 0.872340 (-3427 2300);
PAINT GREEN (-3427 2300);
DISPLAY INVISIBLE (-3427 2300);
FORCEADD TAP..1
(-3425 2250);
FORCEPROP 3 LASTPIN (-3475 2250) SIG_NAME M_G_CPU1_SA_CB<4>
J 0
(-3465 2260);
DISPLAY 0.659574 (-3465 2260);
PAINT MONO (-3465 2260);
DISPLAY INVISIBLE (-3465 2260);
FORCEPROP 1 LASTPIN (-3475 2250) BN 4
J 0
(-3487 2258);
DISPLAY 0.489362 (-3487 2258);
PAINT GREEN (-3487 2258);
FORCEPROP 2 LAST CDS_LIB mstr_standard
J 2
(-3425 2250);
DISPLAY 0.723404 (-3425 2250);
PAINT MONO (-3425 2250);
DISPLAY INVISIBLE (-3425 2250);
FORCEPROP 1 LAST BODY_TYPE PLUMBING
J 0
(-3425 2300);
DISPLAY 0.872340 (-3425 2300);
PAINT GREEN (-3425 2300);
DISPLAY INVISIBLE (-3425 2300);
FORCEPROP 1 LAST HDL_TAP TRUE
J 0
(-3100 2125);
DISPLAY 0.872340 (-3100 2125);
DISPLAY INVISIBLE (-3100 2125);
FORCEPROP 1 LAST PATH I239
J 0
(-3427 2250);
DISPLAY 0.872340 (-3427 2250);
PAINT GREEN (-3427 2250);
DISPLAY INVISIBLE (-3427 2250);
FORCEADD TAP..1
(-3425 2200);
FORCEPROP 3 LASTPIN (-3475 2200) SIG_NAME M_G_CPU1_SA_CB<5>
J 0
(-3465 2210);
DISPLAY 0.659574 (-3465 2210);
PAINT MONO (-3465 2210);
DISPLAY INVISIBLE (-3465 2210);
FORCEPROP 1 LASTPIN (-3475 2200) BN 5
J 0
(-3487 2208);
DISPLAY 0.489362 (-3487 2208);
PAINT GREEN (-3487 2208);
FORCEPROP 2 LAST CDS_LIB mstr_standard
J 2
(-3425 2200);
DISPLAY 0.723404 (-3425 2200);
PAINT MONO (-3425 2200);
DISPLAY INVISIBLE (-3425 2200);
FORCEPROP 1 LAST BODY_TYPE PLUMBING
J 0
(-3425 2250);
DISPLAY 0.872340 (-3425 2250);
PAINT GREEN (-3425 2250);
DISPLAY INVISIBLE (-3425 2250);
FORCEPROP 1 LAST HDL_TAP TRUE
J 0
(-3100 2075);
DISPLAY 0.872340 (-3100 2075);
DISPLAY INVISIBLE (-3100 2075);
FORCEPROP 1 LAST PATH I240
J 0
(-3427 2200);
DISPLAY 0.872340 (-3427 2200);
PAINT GREEN (-3427 2200);
DISPLAY INVISIBLE (-3427 2200);
FORCEADD TAP..1
(-3425 2150);
FORCEPROP 3 LASTPIN (-3475 2150) SIG_NAME M_G_CPU1_SA_CB<6>
J 0
(-3465 2160);
DISPLAY 0.659574 (-3465 2160);
PAINT MONO (-3465 2160);
DISPLAY INVISIBLE (-3465 2160);
FORCEPROP 1 LASTPIN (-3475 2150) BN 6
J 0
(-3487 2158);
DISPLAY 0.489362 (-3487 2158);
PAINT GREEN (-3487 2158);
FORCEPROP 2 LAST CDS_LIB mstr_standard
J 2
(-3425 2150);
DISPLAY 0.723404 (-3425 2150);
PAINT MONO (-3425 2150);
DISPLAY INVISIBLE (-3425 2150);
FORCEPROP 1 LAST BODY_TYPE PLUMBING
J 0
(-3425 2200);
DISPLAY 0.872340 (-3425 2200);
PAINT GREEN (-3425 2200);
DISPLAY INVISIBLE (-3425 2200);
FORCEPROP 1 LAST HDL_TAP TRUE
J 0
(-3100 2025);
DISPLAY 0.872340 (-3100 2025);
DISPLAY INVISIBLE (-3100 2025);
FORCEPROP 1 LAST PATH I241
J 0
(-3427 2150);
DISPLAY 0.872340 (-3427 2150);
PAINT GREEN (-3427 2150);
DISPLAY INVISIBLE (-3427 2150);
FORCEADD TAP..1
(-3425 2100);
FORCEPROP 3 LASTPIN (-3475 2100) SIG_NAME M_G_CPU1_SA_CB<7>
J 0
(-3465 2110);
DISPLAY 0.659574 (-3465 2110);
PAINT MONO (-3465 2110);
DISPLAY INVISIBLE (-3465 2110);
FORCEPROP 1 LASTPIN (-3475 2100) BN 7
J 0
(-3487 2108);
DISPLAY 0.489362 (-3487 2108);
PAINT GREEN (-3487 2108);
FORCEPROP 2 LAST CDS_LIB mstr_standard
J 2
(-3425 2100);
DISPLAY 0.723404 (-3425 2100);
PAINT MONO (-3425 2100);
DISPLAY INVISIBLE (-3425 2100);
FORCEPROP 1 LAST BODY_TYPE PLUMBING
J 0
(-3425 2150);
DISPLAY 0.872340 (-3425 2150);
PAINT GREEN (-3425 2150);
DISPLAY INVISIBLE (-3425 2150);
FORCEPROP 1 LAST HDL_TAP TRUE
J 0
(-3100 1975);
DISPLAY 0.872340 (-3100 1975);
DISPLAY INVISIBLE (-3100 1975);
FORCEPROP 1 LAST PATH I242
J 0
(-3427 2100);
DISPLAY 0.872340 (-3427 2100);
PAINT GREEN (-3427 2100);
DISPLAY INVISIBLE (-3427 2100);
FORCEADD OFFPAGE..6
R 2
(-2825 2050);
FORCEPROP 2 LAST $XR0 104 
J 0
(-2611 2050);
DISPLAY 0.638298 (-2611 2050);
PAINT MONO (-2611 2050);
FORCEPROP 2 LAST CDS_LIB mstr_standard
J 2
(-2825 2050);
DISPLAY 0.723404 (-2825 2050);
PAINT MONO (-2825 2050);
DISPLAY INVISIBLE (-2825 2050);
FORCEPROP 1 LAST OFFPAGE TRUE
J 2
(-3150 1925);
DISPLAY 0.872340 (-3150 1925);
PAINT GREEN (-3150 1925);
DISPLAY INVISIBLE (-3150 1925);
FORCEPROP 1 LAST COMMENT_BODY TRUE
J 2
(-2925 1975);
DISPLAY 0.872340 (-2925 1975);
PAINT GREEN (-2925 1975);
DISPLAY INVISIBLE (-2925 1975);
FORCEPROP 2 LAST PATH I243
J 0
(-2600 2100);
DISPLAY 1.021277 (-2600 2100);
DISPLAY INVISIBLE (-2600 2100);
FORCEADD TAP..1
(-3425 1950);
FORCEPROP 3 LASTPIN (-3475 1950) SIG_NAME M_G_CPU1_SB_CB<1>
J 0
(-3465 1960);
DISPLAY 0.659574 (-3465 1960);
PAINT MONO (-3465 1960);
DISPLAY INVISIBLE (-3465 1960);
FORCEPROP 1 LASTPIN (-3475 1950) BN 1
J 0
(-3487 1958);
DISPLAY 0.489362 (-3487 1958);
PAINT GREEN (-3487 1958);
FORCEPROP 2 LAST CDS_LIB mstr_standard
J 2
(-3425 1950);
DISPLAY 0.723404 (-3425 1950);
PAINT MONO (-3425 1950);
DISPLAY INVISIBLE (-3425 1950);
FORCEPROP 1 LAST BODY_TYPE PLUMBING
J 0
(-3425 2000);
DISPLAY 0.872340 (-3425 2000);
PAINT GREEN (-3425 2000);
DISPLAY INVISIBLE (-3425 2000);
FORCEPROP 1 LAST HDL_TAP TRUE
J 0
(-3100 1825);
DISPLAY 0.872340 (-3100 1825);
DISPLAY INVISIBLE (-3100 1825);
FORCEPROP 1 LAST PATH I244
J 0
(-3427 1950);
DISPLAY 0.872340 (-3427 1950);
PAINT GREEN (-3427 1950);
DISPLAY INVISIBLE (-3427 1950);
FORCEADD TAP..1
(-3425 2000);
FORCEPROP 3 LASTPIN (-3475 2000) SIG_NAME M_G_CPU1_SB_CB<0>
J 0
(-3465 2010);
DISPLAY 0.659574 (-3465 2010);
PAINT MONO (-3465 2010);
DISPLAY INVISIBLE (-3465 2010);
FORCEPROP 1 LASTPIN (-3475 2000) BN 0
J 0
(-3487 2008);
DISPLAY 0.489362 (-3487 2008);
PAINT GREEN (-3487 2008);
FORCEPROP 2 LAST CDS_LIB mstr_standard
J 2
(-3425 2000);
DISPLAY 0.723404 (-3425 2000);
PAINT MONO (-3425 2000);
DISPLAY INVISIBLE (-3425 2000);
FORCEPROP 1 LAST BODY_TYPE PLUMBING
J 0
(-3425 2050);
DISPLAY 0.872340 (-3425 2050);
PAINT GREEN (-3425 2050);
DISPLAY INVISIBLE (-3425 2050);
FORCEPROP 1 LAST HDL_TAP TRUE
J 0
(-3100 1875);
DISPLAY 0.872340 (-3100 1875);
DISPLAY INVISIBLE (-3100 1875);
FORCEPROP 1 LAST PATH I245
J 0
(-3427 2000);
DISPLAY 0.872340 (-3427 2000);
PAINT GREEN (-3427 2000);
DISPLAY INVISIBLE (-3427 2000);
FORCEADD TAP..1
(-3425 1900);
FORCEPROP 3 LASTPIN (-3475 1900) SIG_NAME M_G_CPU1_SB_CB<2>
J 0
(-3465 1910);
DISPLAY 0.659574 (-3465 1910);
PAINT MONO (-3465 1910);
DISPLAY INVISIBLE (-3465 1910);
FORCEPROP 1 LASTPIN (-3475 1900) BN 2
J 0
(-3487 1908);
DISPLAY 0.489362 (-3487 1908);
PAINT GREEN (-3487 1908);
FORCEPROP 2 LAST CDS_LIB mstr_standard
J 2
(-3425 1900);
DISPLAY 0.723404 (-3425 1900);
PAINT MONO (-3425 1900);
DISPLAY INVISIBLE (-3425 1900);
FORCEPROP 1 LAST BODY_TYPE PLUMBING
J 0
(-3425 1950);
DISPLAY 0.872340 (-3425 1950);
PAINT GREEN (-3425 1950);
DISPLAY INVISIBLE (-3425 1950);
FORCEPROP 1 LAST HDL_TAP TRUE
J 0
(-3100 1775);
DISPLAY 0.872340 (-3100 1775);
DISPLAY INVISIBLE (-3100 1775);
FORCEPROP 1 LAST PATH I246
J 0
(-3427 1900);
DISPLAY 0.872340 (-3427 1900);
PAINT GREEN (-3427 1900);
DISPLAY INVISIBLE (-3427 1900);
FORCEADD TAP..1
(-3425 1800);
FORCEPROP 3 LASTPIN (-3475 1800) SIG_NAME M_G_CPU1_SB_CB<4>
J 0
(-3465 1810);
DISPLAY 0.659574 (-3465 1810);
PAINT MONO (-3465 1810);
DISPLAY INVISIBLE (-3465 1810);
FORCEPROP 1 LASTPIN (-3475 1800) BN 4
J 0
(-3487 1808);
DISPLAY 0.489362 (-3487 1808);
PAINT GREEN (-3487 1808);
FORCEPROP 2 LAST CDS_LIB mstr_standard
J 2
(-3425 1800);
DISPLAY 0.723404 (-3425 1800);
PAINT MONO (-3425 1800);
DISPLAY INVISIBLE (-3425 1800);
FORCEPROP 1 LAST BODY_TYPE PLUMBING
J 0
(-3425 1850);
DISPLAY 0.872340 (-3425 1850);
PAINT GREEN (-3425 1850);
DISPLAY INVISIBLE (-3425 1850);
FORCEPROP 1 LAST HDL_TAP TRUE
J 0
(-3100 1675);
DISPLAY 0.872340 (-3100 1675);
DISPLAY INVISIBLE (-3100 1675);
FORCEPROP 1 LAST PATH I247
J 0
(-3427 1800);
DISPLAY 0.872340 (-3427 1800);
PAINT GREEN (-3427 1800);
DISPLAY INVISIBLE (-3427 1800);
FORCEADD TAP..1
(-3425 1850);
FORCEPROP 3 LASTPIN (-3475 1850) SIG_NAME M_G_CPU1_SB_CB<3>
J 0
(-3465 1860);
DISPLAY 0.659574 (-3465 1860);
PAINT MONO (-3465 1860);
DISPLAY INVISIBLE (-3465 1860);
FORCEPROP 1 LASTPIN (-3475 1850) BN 3
J 0
(-3487 1858);
DISPLAY 0.489362 (-3487 1858);
PAINT GREEN (-3487 1858);
FORCEPROP 2 LAST CDS_LIB mstr_standard
J 2
(-3425 1850);
DISPLAY 0.723404 (-3425 1850);
PAINT MONO (-3425 1850);
DISPLAY INVISIBLE (-3425 1850);
FORCEPROP 1 LAST BODY_TYPE PLUMBING
J 0
(-3425 1900);
DISPLAY 0.872340 (-3425 1900);
PAINT GREEN (-3425 1900);
DISPLAY INVISIBLE (-3425 1900);
FORCEPROP 1 LAST HDL_TAP TRUE
J 0
(-3100 1725);
DISPLAY 0.872340 (-3100 1725);
DISPLAY INVISIBLE (-3100 1725);
FORCEPROP 1 LAST PATH I248
J 0
(-3427 1850);
DISPLAY 0.872340 (-3427 1850);
PAINT GREEN (-3427 1850);
DISPLAY INVISIBLE (-3427 1850);
FORCEADD TAP..1
(-3425 1700);
FORCEPROP 3 LASTPIN (-3475 1700) SIG_NAME M_G_CPU1_SB_CB<6>
J 0
(-3465 1710);
DISPLAY 0.659574 (-3465 1710);
PAINT MONO (-3465 1710);
DISPLAY INVISIBLE (-3465 1710);
FORCEPROP 1 LASTPIN (-3475 1700) BN 6
J 0
(-3487 1708);
DISPLAY 0.489362 (-3487 1708);
PAINT GREEN (-3487 1708);
FORCEPROP 2 LAST CDS_LIB mstr_standard
J 2
(-3425 1700);
DISPLAY 0.723404 (-3425 1700);
PAINT MONO (-3425 1700);
DISPLAY INVISIBLE (-3425 1700);
FORCEPROP 1 LAST BODY_TYPE PLUMBING
J 0
(-3425 1750);
DISPLAY 0.872340 (-3425 1750);
PAINT GREEN (-3425 1750);
DISPLAY INVISIBLE (-3425 1750);
FORCEPROP 1 LAST HDL_TAP TRUE
J 0
(-3100 1575);
DISPLAY 0.872340 (-3100 1575);
DISPLAY INVISIBLE (-3100 1575);
FORCEPROP 1 LAST PATH I249
J 0
(-3427 1700);
DISPLAY 0.872340 (-3427 1700);
PAINT GREEN (-3427 1700);
DISPLAY INVISIBLE (-3427 1700);
FORCEADD TAP..1
(-3425 1750);
FORCEPROP 3 LASTPIN (-3475 1750) SIG_NAME M_G_CPU1_SB_CB<5>
J 0
(-3465 1760);
DISPLAY 0.659574 (-3465 1760);
PAINT MONO (-3465 1760);
DISPLAY INVISIBLE (-3465 1760);
FORCEPROP 1 LASTPIN (-3475 1750) BN 5
J 0
(-3487 1758);
DISPLAY 0.489362 (-3487 1758);
PAINT GREEN (-3487 1758);
FORCEPROP 2 LAST CDS_LIB mstr_standard
J 2
(-3425 1750);
DISPLAY 0.723404 (-3425 1750);
PAINT MONO (-3425 1750);
DISPLAY INVISIBLE (-3425 1750);
FORCEPROP 1 LAST BODY_TYPE PLUMBING
J 0
(-3425 1800);
DISPLAY 0.872340 (-3425 1800);
PAINT GREEN (-3425 1800);
DISPLAY INVISIBLE (-3425 1800);
FORCEPROP 1 LAST HDL_TAP TRUE
J 0
(-3100 1625);
DISPLAY 0.872340 (-3100 1625);
DISPLAY INVISIBLE (-3100 1625);
FORCEPROP 1 LAST PATH I250
J 0
(-3427 1750);
DISPLAY 0.872340 (-3427 1750);
PAINT GREEN (-3427 1750);
DISPLAY INVISIBLE (-3427 1750);
FORCEADD TAP..1
(-3425 1650);
FORCEPROP 3 LASTPIN (-3475 1650) SIG_NAME M_G_CPU1_SB_CB<7>
J 0
(-3465 1660);
DISPLAY 0.659574 (-3465 1660);
PAINT MONO (-3465 1660);
DISPLAY INVISIBLE (-3465 1660);
FORCEPROP 1 LASTPIN (-3475 1650) BN 7
J 0
(-3487 1658);
DISPLAY 0.489362 (-3487 1658);
PAINT GREEN (-3487 1658);
FORCEPROP 2 LAST CDS_LIB mstr_standard
J 2
(-3425 1650);
DISPLAY 0.723404 (-3425 1650);
PAINT MONO (-3425 1650);
DISPLAY INVISIBLE (-3425 1650);
FORCEPROP 1 LAST BODY_TYPE PLUMBING
J 0
(-3425 1700);
DISPLAY 0.872340 (-3425 1700);
PAINT GREEN (-3425 1700);
DISPLAY INVISIBLE (-3425 1700);
FORCEPROP 1 LAST HDL_TAP TRUE
J 0
(-3100 1525);
DISPLAY 0.872340 (-3100 1525);
DISPLAY INVISIBLE (-3100 1525);
FORCEPROP 1 LAST PATH I251
J 0
(-3427 1650);
DISPLAY 0.872340 (-3427 1650);
PAINT GREEN (-3427 1650);
DISPLAY INVISIBLE (-3427 1650);
FORCEADD TAP..1
R 2
(-5850 6050);
FORCEPROP 3 LASTPIN (-5800 6050) SIG_NAME M_G_CPU1_SA_DQS_DP<0>
J 0
(-5790 6060);
DISPLAY 0.659574 (-5790 6060);
PAINT MONO (-5790 6060);
DISPLAY INVISIBLE (-5790 6060);
FORCEPROP 1 LASTPIN (-5800 6050) BN 0
J 2
(-5788 6058);
DISPLAY 0.489362 (-5788 6058);
PAINT GREEN (-5788 6058);
FORCEPROP 2 LAST CDS_LIB mstr_standard
J 2
(-5850 6050);
DISPLAY 0.723404 (-5850 6050);
PAINT MONO (-5850 6050);
DISPLAY INVISIBLE (-5850 6050);
FORCEPROP 1 LAST BODY_TYPE PLUMBING
J 2
(-5850 6100);
DISPLAY 0.872340 (-5850 6100);
PAINT GREEN (-5850 6100);
DISPLAY INVISIBLE (-5850 6100);
FORCEPROP 1 LAST HDL_TAP TRUE
J 2
(-6175 5925);
DISPLAY 0.872340 (-6175 5925);
DISPLAY INVISIBLE (-6175 5925);
FORCEPROP 1 LAST PATH I252
J 2
(-5848 6050);
DISPLAY 0.872340 (-5848 6050);
PAINT GREEN (-5848 6050);
DISPLAY INVISIBLE (-5848 6050);
FORCEADD TAP..1
R 2
(-5850 5950);
FORCEPROP 3 LASTPIN (-5800 5950) SIG_NAME M_G_CPU1_SA_DQS_DP<1>
J 0
(-5790 5960);
DISPLAY 0.659574 (-5790 5960);
PAINT MONO (-5790 5960);
DISPLAY INVISIBLE (-5790 5960);
FORCEPROP 1 LASTPIN (-5800 5950) BN 1
J 2
(-5788 5958);
DISPLAY 0.489362 (-5788 5958);
PAINT GREEN (-5788 5958);
FORCEPROP 2 LAST CDS_LIB mstr_standard
J 2
(-5850 5950);
DISPLAY 0.723404 (-5850 5950);
PAINT MONO (-5850 5950);
DISPLAY INVISIBLE (-5850 5950);
FORCEPROP 1 LAST BODY_TYPE PLUMBING
J 2
(-5850 6000);
DISPLAY 0.872340 (-5850 6000);
PAINT GREEN (-5850 6000);
DISPLAY INVISIBLE (-5850 6000);
FORCEPROP 1 LAST HDL_TAP TRUE
J 2
(-6175 5825);
DISPLAY 0.872340 (-6175 5825);
DISPLAY INVISIBLE (-6175 5825);
FORCEPROP 1 LAST PATH I253
J 2
(-5848 5950);
DISPLAY 0.872340 (-5848 5950);
PAINT GREEN (-5848 5950);
DISPLAY INVISIBLE (-5848 5950);
FORCEADD TAP..1
R 2
(-5850 5850);
FORCEPROP 3 LASTPIN (-5800 5850) SIG_NAME M_G_CPU1_SA_DQS_DP<2>
J 0
(-5790 5860);
DISPLAY 0.659574 (-5790 5860);
PAINT MONO (-5790 5860);
DISPLAY INVISIBLE (-5790 5860);
FORCEPROP 1 LASTPIN (-5800 5850) BN 2
J 2
(-5788 5858);
DISPLAY 0.489362 (-5788 5858);
PAINT GREEN (-5788 5858);
FORCEPROP 2 LAST CDS_LIB mstr_standard
J 2
(-5850 5850);
DISPLAY 0.723404 (-5850 5850);
PAINT MONO (-5850 5850);
DISPLAY INVISIBLE (-5850 5850);
FORCEPROP 1 LAST BODY_TYPE PLUMBING
J 2
(-5850 5900);
DISPLAY 0.872340 (-5850 5900);
PAINT GREEN (-5850 5900);
DISPLAY INVISIBLE (-5850 5900);
FORCEPROP 1 LAST HDL_TAP TRUE
J 2
(-6175 5725);
DISPLAY 0.872340 (-6175 5725);
DISPLAY INVISIBLE (-6175 5725);
FORCEPROP 1 LAST PATH I254
J 2
(-5848 5850);
DISPLAY 0.872340 (-5848 5850);
PAINT GREEN (-5848 5850);
DISPLAY INVISIBLE (-5848 5850);
FORCEADD TAP..1
R 2
(-5850 5750);
FORCEPROP 3 LASTPIN (-5800 5750) SIG_NAME M_G_CPU1_SA_DQS_DP<3>
J 0
(-5790 5760);
DISPLAY 0.659574 (-5790 5760);
PAINT MONO (-5790 5760);
DISPLAY INVISIBLE (-5790 5760);
FORCEPROP 1 LASTPIN (-5800 5750) BN 3
J 2
(-5788 5758);
DISPLAY 0.489362 (-5788 5758);
PAINT GREEN (-5788 5758);
FORCEPROP 2 LAST CDS_LIB mstr_standard
J 2
(-5850 5750);
DISPLAY 0.723404 (-5850 5750);
PAINT MONO (-5850 5750);
DISPLAY INVISIBLE (-5850 5750);
FORCEPROP 1 LAST BODY_TYPE PLUMBING
J 2
(-5850 5800);
DISPLAY 0.872340 (-5850 5800);
PAINT GREEN (-5850 5800);
DISPLAY INVISIBLE (-5850 5800);
FORCEPROP 1 LAST HDL_TAP TRUE
J 2
(-6175 5625);
DISPLAY 0.872340 (-6175 5625);
DISPLAY INVISIBLE (-6175 5625);
FORCEPROP 1 LAST PATH I255
J 2
(-5848 5750);
DISPLAY 0.872340 (-5848 5750);
PAINT GREEN (-5848 5750);
DISPLAY INVISIBLE (-5848 5750);
FORCEADD TAP..1
R 2
(-5850 5650);
FORCEPROP 3 LASTPIN (-5800 5650) SIG_NAME M_G_CPU1_SA_DQS_DP<4>
J 0
(-5790 5660);
DISPLAY 0.659574 (-5790 5660);
PAINT MONO (-5790 5660);
DISPLAY INVISIBLE (-5790 5660);
FORCEPROP 1 LASTPIN (-5800 5650) BN 4
J 2
(-5788 5658);
DISPLAY 0.489362 (-5788 5658);
PAINT GREEN (-5788 5658);
FORCEPROP 2 LAST CDS_LIB mstr_standard
J 2
(-5850 5650);
DISPLAY 0.723404 (-5850 5650);
PAINT MONO (-5850 5650);
DISPLAY INVISIBLE (-5850 5650);
FORCEPROP 1 LAST BODY_TYPE PLUMBING
J 2
(-5850 5700);
DISPLAY 0.872340 (-5850 5700);
PAINT GREEN (-5850 5700);
DISPLAY INVISIBLE (-5850 5700);
FORCEPROP 1 LAST HDL_TAP TRUE
J 2
(-6175 5525);
DISPLAY 0.872340 (-6175 5525);
DISPLAY INVISIBLE (-6175 5525);
FORCEPROP 1 LAST PATH I256
J 2
(-5848 5650);
DISPLAY 0.872340 (-5848 5650);
PAINT GREEN (-5848 5650);
DISPLAY INVISIBLE (-5848 5650);
FORCEADD TAP..1
R 2
(-6050 6000);
FORCEPROP 3 LASTPIN (-6000 6000) SIG_NAME M_G_CPU1_SA_DQS_DN<0>
J 0
(-5990 6010);
DISPLAY 0.659574 (-5990 6010);
PAINT MONO (-5990 6010);
DISPLAY INVISIBLE (-5990 6010);
FORCEPROP 1 LASTPIN (-6000 6000) BN 0
J 2
(-5988 6008);
DISPLAY 0.489362 (-5988 6008);
PAINT GREEN (-5988 6008);
FORCEPROP 2 LAST CDS_LIB mstr_standard
J 2
(-6050 6000);
DISPLAY 0.723404 (-6050 6000);
PAINT MONO (-6050 6000);
DISPLAY INVISIBLE (-6050 6000);
FORCEPROP 1 LAST BODY_TYPE PLUMBING
J 2
(-6050 6050);
DISPLAY 0.872340 (-6050 6050);
PAINT GREEN (-6050 6050);
DISPLAY INVISIBLE (-6050 6050);
FORCEPROP 1 LAST HDL_TAP TRUE
J 2
(-6375 5875);
DISPLAY 0.872340 (-6375 5875);
DISPLAY INVISIBLE (-6375 5875);
FORCEPROP 1 LAST PATH I257
J 2
(-6048 6000);
DISPLAY 0.872340 (-6048 6000);
PAINT GREEN (-6048 6000);
DISPLAY INVISIBLE (-6048 6000);
FORCEADD TAP..1
R 2
(-6050 5900);
FORCEPROP 3 LASTPIN (-6000 5900) SIG_NAME M_G_CPU1_SA_DQS_DN<1>
J 0
(-5990 5910);
DISPLAY 0.659574 (-5990 5910);
PAINT MONO (-5990 5910);
DISPLAY INVISIBLE (-5990 5910);
FORCEPROP 1 LASTPIN (-6000 5900) BN 1
J 2
(-5988 5908);
DISPLAY 0.489362 (-5988 5908);
PAINT GREEN (-5988 5908);
FORCEPROP 2 LAST CDS_LIB mstr_standard
J 2
(-6050 5900);
DISPLAY 0.723404 (-6050 5900);
PAINT MONO (-6050 5900);
DISPLAY INVISIBLE (-6050 5900);
FORCEPROP 1 LAST BODY_TYPE PLUMBING
J 2
(-6050 5950);
DISPLAY 0.872340 (-6050 5950);
PAINT GREEN (-6050 5950);
DISPLAY INVISIBLE (-6050 5950);
FORCEPROP 1 LAST HDL_TAP TRUE
J 2
(-6375 5775);
DISPLAY 0.872340 (-6375 5775);
DISPLAY INVISIBLE (-6375 5775);
FORCEPROP 1 LAST PATH I258
J 2
(-6048 5900);
DISPLAY 0.872340 (-6048 5900);
PAINT GREEN (-6048 5900);
DISPLAY INVISIBLE (-6048 5900);
FORCEADD TAP..1
R 2
(-6050 5800);
FORCEPROP 3 LASTPIN (-6000 5800) SIG_NAME M_G_CPU1_SA_DQS_DN<2>
J 0
(-5990 5810);
DISPLAY 0.659574 (-5990 5810);
PAINT MONO (-5990 5810);
DISPLAY INVISIBLE (-5990 5810);
FORCEPROP 1 LASTPIN (-6000 5800) BN 2
J 2
(-5988 5808);
DISPLAY 0.489362 (-5988 5808);
PAINT GREEN (-5988 5808);
FORCEPROP 2 LAST CDS_LIB mstr_standard
J 2
(-6050 5800);
DISPLAY 0.723404 (-6050 5800);
PAINT MONO (-6050 5800);
DISPLAY INVISIBLE (-6050 5800);
FORCEPROP 1 LAST BODY_TYPE PLUMBING
J 2
(-6050 5850);
DISPLAY 0.872340 (-6050 5850);
PAINT GREEN (-6050 5850);
DISPLAY INVISIBLE (-6050 5850);
FORCEPROP 1 LAST HDL_TAP TRUE
J 2
(-6375 5675);
DISPLAY 0.872340 (-6375 5675);
DISPLAY INVISIBLE (-6375 5675);
FORCEPROP 1 LAST PATH I259
J 2
(-6048 5800);
DISPLAY 0.872340 (-6048 5800);
PAINT GREEN (-6048 5800);
DISPLAY INVISIBLE (-6048 5800);
FORCEADD TAP..1
R 2
(-6050 5700);
FORCEPROP 3 LASTPIN (-6000 5700) SIG_NAME M_G_CPU1_SA_DQS_DN<3>
J 0
(-5990 5710);
DISPLAY 0.659574 (-5990 5710);
PAINT MONO (-5990 5710);
DISPLAY INVISIBLE (-5990 5710);
FORCEPROP 1 LASTPIN (-6000 5700) BN 3
J 2
(-5988 5708);
DISPLAY 0.489362 (-5988 5708);
PAINT GREEN (-5988 5708);
FORCEPROP 2 LAST CDS_LIB mstr_standard
J 2
(-6050 5700);
DISPLAY 0.723404 (-6050 5700);
PAINT MONO (-6050 5700);
DISPLAY INVISIBLE (-6050 5700);
FORCEPROP 1 LAST BODY_TYPE PLUMBING
J 2
(-6050 5750);
DISPLAY 0.872340 (-6050 5750);
PAINT GREEN (-6050 5750);
DISPLAY INVISIBLE (-6050 5750);
FORCEPROP 1 LAST HDL_TAP TRUE
J 2
(-6375 5575);
DISPLAY 0.872340 (-6375 5575);
DISPLAY INVISIBLE (-6375 5575);
FORCEPROP 1 LAST PATH I260
J 2
(-6048 5700);
DISPLAY 0.872340 (-6048 5700);
PAINT GREEN (-6048 5700);
DISPLAY INVISIBLE (-6048 5700);
FORCEADD TAP..1
R 2
(-5850 5550);
FORCEPROP 3 LASTPIN (-5800 5550) SIG_NAME M_G_CPU1_SA_DQS_DP<5>
J 0
(-5790 5560);
DISPLAY 0.659574 (-5790 5560);
PAINT MONO (-5790 5560);
DISPLAY INVISIBLE (-5790 5560);
FORCEPROP 1 LASTPIN (-5800 5550) BN 5
J 2
(-5788 5558);
DISPLAY 0.489362 (-5788 5558);
PAINT GREEN (-5788 5558);
FORCEPROP 2 LAST CDS_LIB mstr_standard
J 2
(-5850 5550);
DISPLAY 0.723404 (-5850 5550);
PAINT MONO (-5850 5550);
DISPLAY INVISIBLE (-5850 5550);
FORCEPROP 1 LAST BODY_TYPE PLUMBING
J 2
(-5850 5600);
DISPLAY 0.872340 (-5850 5600);
PAINT GREEN (-5850 5600);
DISPLAY INVISIBLE (-5850 5600);
FORCEPROP 1 LAST HDL_TAP TRUE
J 2
(-6175 5425);
DISPLAY 0.872340 (-6175 5425);
DISPLAY INVISIBLE (-6175 5425);
FORCEPROP 1 LAST PATH I261
J 2
(-5848 5550);
DISPLAY 0.872340 (-5848 5550);
PAINT GREEN (-5848 5550);
DISPLAY INVISIBLE (-5848 5550);
FORCEADD TAP..1
R 2
(-5850 5450);
FORCEPROP 3 LASTPIN (-5800 5450) SIG_NAME M_G_CPU1_SA_DQS_DP<6>
J 0
(-5790 5460);
DISPLAY 0.659574 (-5790 5460);
PAINT MONO (-5790 5460);
DISPLAY INVISIBLE (-5790 5460);
FORCEPROP 1 LASTPIN (-5800 5450) BN 6
J 2
(-5788 5458);
DISPLAY 0.489362 (-5788 5458);
PAINT GREEN (-5788 5458);
FORCEPROP 2 LAST CDS_LIB mstr_standard
J 2
(-5850 5450);
DISPLAY 0.723404 (-5850 5450);
PAINT MONO (-5850 5450);
DISPLAY INVISIBLE (-5850 5450);
FORCEPROP 1 LAST BODY_TYPE PLUMBING
J 2
(-5850 5500);
DISPLAY 0.872340 (-5850 5500);
PAINT GREEN (-5850 5500);
DISPLAY INVISIBLE (-5850 5500);
FORCEPROP 1 LAST HDL_TAP TRUE
J 2
(-6175 5325);
DISPLAY 0.872340 (-6175 5325);
DISPLAY INVISIBLE (-6175 5325);
FORCEPROP 1 LAST PATH I262
J 2
(-5848 5450);
DISPLAY 0.872340 (-5848 5450);
PAINT GREEN (-5848 5450);
DISPLAY INVISIBLE (-5848 5450);
FORCEADD TAP..1
R 2
(-5850 5350);
FORCEPROP 3 LASTPIN (-5800 5350) SIG_NAME M_G_CPU1_SA_DQS_DP<7>
J 0
(-5790 5360);
DISPLAY 0.659574 (-5790 5360);
PAINT MONO (-5790 5360);
DISPLAY INVISIBLE (-5790 5360);
FORCEPROP 1 LASTPIN (-5800 5350) BN 7
J 2
(-5788 5358);
DISPLAY 0.489362 (-5788 5358);
PAINT GREEN (-5788 5358);
FORCEPROP 2 LAST CDS_LIB mstr_standard
J 2
(-5850 5350);
DISPLAY 0.723404 (-5850 5350);
PAINT MONO (-5850 5350);
DISPLAY INVISIBLE (-5850 5350);
FORCEPROP 1 LAST BODY_TYPE PLUMBING
J 2
(-5850 5400);
DISPLAY 0.872340 (-5850 5400);
PAINT GREEN (-5850 5400);
DISPLAY INVISIBLE (-5850 5400);
FORCEPROP 1 LAST HDL_TAP TRUE
J 2
(-6175 5225);
DISPLAY 0.872340 (-6175 5225);
DISPLAY INVISIBLE (-6175 5225);
FORCEPROP 1 LAST PATH I263
J 2
(-5848 5350);
DISPLAY 0.872340 (-5848 5350);
PAINT GREEN (-5848 5350);
DISPLAY INVISIBLE (-5848 5350);
FORCEADD TAP..1
R 2
(-5850 5250);
FORCEPROP 3 LASTPIN (-5800 5250) SIG_NAME M_G_CPU1_SA_DQS_DP<8>
J 0
(-5790 5260);
DISPLAY 0.659574 (-5790 5260);
PAINT MONO (-5790 5260);
DISPLAY INVISIBLE (-5790 5260);
FORCEPROP 1 LASTPIN (-5800 5250) BN 8
J 2
(-5788 5258);
DISPLAY 0.489362 (-5788 5258);
PAINT GREEN (-5788 5258);
FORCEPROP 2 LAST CDS_LIB mstr_standard
J 2
(-5850 5250);
DISPLAY 0.723404 (-5850 5250);
PAINT MONO (-5850 5250);
DISPLAY INVISIBLE (-5850 5250);
FORCEPROP 1 LAST BODY_TYPE PLUMBING
J 2
(-5850 5300);
DISPLAY 0.872340 (-5850 5300);
PAINT GREEN (-5850 5300);
DISPLAY INVISIBLE (-5850 5300);
FORCEPROP 1 LAST HDL_TAP TRUE
J 2
(-6175 5125);
DISPLAY 0.872340 (-6175 5125);
DISPLAY INVISIBLE (-6175 5125);
FORCEPROP 1 LAST PATH I264
J 2
(-5848 5250);
DISPLAY 0.872340 (-5848 5250);
PAINT GREEN (-5848 5250);
DISPLAY INVISIBLE (-5848 5250);
FORCEADD TAP..1
R 2
(-5850 5150);
FORCEPROP 3 LASTPIN (-5800 5150) SIG_NAME M_G_CPU1_SA_DQS_DP<9>
J 0
(-5790 5160);
DISPLAY 0.659574 (-5790 5160);
PAINT MONO (-5790 5160);
DISPLAY INVISIBLE (-5790 5160);
FORCEPROP 1 LASTPIN (-5800 5150) BN 9
J 2
(-5788 5158);
DISPLAY 0.489362 (-5788 5158);
PAINT GREEN (-5788 5158);
FORCEPROP 2 LAST CDS_LIB mstr_standard
J 2
(-5850 5150);
DISPLAY 0.723404 (-5850 5150);
PAINT MONO (-5850 5150);
DISPLAY INVISIBLE (-5850 5150);
FORCEPROP 1 LAST BODY_TYPE PLUMBING
J 2
(-5850 5200);
DISPLAY 0.872340 (-5850 5200);
PAINT GREEN (-5850 5200);
DISPLAY INVISIBLE (-5850 5200);
FORCEPROP 1 LAST HDL_TAP TRUE
J 2
(-6175 5025);
DISPLAY 0.872340 (-6175 5025);
DISPLAY INVISIBLE (-6175 5025);
FORCEPROP 1 LAST PATH I265
J 2
(-5848 5150);
DISPLAY 0.872340 (-5848 5150);
PAINT GREEN (-5848 5150);
DISPLAY INVISIBLE (-5848 5150);
FORCEADD TAP..1
R 2
(-6050 5600);
FORCEPROP 3 LASTPIN (-6000 5600) SIG_NAME M_G_CPU1_SA_DQS_DN<4>
J 0
(-5990 5610);
DISPLAY 0.659574 (-5990 5610);
PAINT MONO (-5990 5610);
DISPLAY INVISIBLE (-5990 5610);
FORCEPROP 1 LASTPIN (-6000 5600) BN 4
J 2
(-5988 5608);
DISPLAY 0.489362 (-5988 5608);
PAINT GREEN (-5988 5608);
FORCEPROP 2 LAST CDS_LIB mstr_standard
J 2
(-6050 5600);
DISPLAY 0.723404 (-6050 5600);
PAINT MONO (-6050 5600);
DISPLAY INVISIBLE (-6050 5600);
FORCEPROP 1 LAST BODY_TYPE PLUMBING
J 2
(-6050 5650);
DISPLAY 0.872340 (-6050 5650);
PAINT GREEN (-6050 5650);
DISPLAY INVISIBLE (-6050 5650);
FORCEPROP 1 LAST HDL_TAP TRUE
J 2
(-6375 5475);
DISPLAY 0.872340 (-6375 5475);
DISPLAY INVISIBLE (-6375 5475);
FORCEPROP 1 LAST PATH I266
J 2
(-6048 5600);
DISPLAY 0.872340 (-6048 5600);
PAINT GREEN (-6048 5600);
DISPLAY INVISIBLE (-6048 5600);
FORCEADD TAP..1
R 2
(-6050 5500);
FORCEPROP 3 LASTPIN (-6000 5500) SIG_NAME M_G_CPU1_SA_DQS_DN<5>
J 0
(-5990 5510);
DISPLAY 0.659574 (-5990 5510);
PAINT MONO (-5990 5510);
DISPLAY INVISIBLE (-5990 5510);
FORCEPROP 1 LASTPIN (-6000 5500) BN 5
J 2
(-5988 5508);
DISPLAY 0.489362 (-5988 5508);
PAINT GREEN (-5988 5508);
FORCEPROP 2 LAST CDS_LIB mstr_standard
J 2
(-6050 5500);
DISPLAY 0.723404 (-6050 5500);
PAINT MONO (-6050 5500);
DISPLAY INVISIBLE (-6050 5500);
FORCEPROP 1 LAST BODY_TYPE PLUMBING
J 2
(-6050 5550);
DISPLAY 0.872340 (-6050 5550);
PAINT GREEN (-6050 5550);
DISPLAY INVISIBLE (-6050 5550);
FORCEPROP 1 LAST HDL_TAP TRUE
J 2
(-6375 5375);
DISPLAY 0.872340 (-6375 5375);
DISPLAY INVISIBLE (-6375 5375);
FORCEPROP 1 LAST PATH I267
J 2
(-6048 5500);
DISPLAY 0.872340 (-6048 5500);
PAINT GREEN (-6048 5500);
DISPLAY INVISIBLE (-6048 5500);
FORCEADD TAP..1
R 2
(-6050 5400);
FORCEPROP 3 LASTPIN (-6000 5400) SIG_NAME M_G_CPU1_SA_DQS_DN<6>
J 0
(-5990 5410);
DISPLAY 0.659574 (-5990 5410);
PAINT MONO (-5990 5410);
DISPLAY INVISIBLE (-5990 5410);
FORCEPROP 1 LASTPIN (-6000 5400) BN 6
J 2
(-5988 5408);
DISPLAY 0.489362 (-5988 5408);
PAINT GREEN (-5988 5408);
FORCEPROP 2 LAST CDS_LIB mstr_standard
J 2
(-6050 5400);
DISPLAY 0.723404 (-6050 5400);
PAINT MONO (-6050 5400);
DISPLAY INVISIBLE (-6050 5400);
FORCEPROP 1 LAST BODY_TYPE PLUMBING
J 2
(-6050 5450);
DISPLAY 0.872340 (-6050 5450);
PAINT GREEN (-6050 5450);
DISPLAY INVISIBLE (-6050 5450);
FORCEPROP 1 LAST HDL_TAP TRUE
J 2
(-6375 5275);
DISPLAY 0.872340 (-6375 5275);
DISPLAY INVISIBLE (-6375 5275);
FORCEPROP 1 LAST PATH I268
J 2
(-6048 5400);
DISPLAY 0.872340 (-6048 5400);
PAINT GREEN (-6048 5400);
DISPLAY INVISIBLE (-6048 5400);
FORCEADD TAP..1
R 2
(-6050 5300);
FORCEPROP 3 LASTPIN (-6000 5300) SIG_NAME M_G_CPU1_SA_DQS_DN<7>
J 0
(-5990 5310);
DISPLAY 0.659574 (-5990 5310);
PAINT MONO (-5990 5310);
DISPLAY INVISIBLE (-5990 5310);
FORCEPROP 1 LASTPIN (-6000 5300) BN 7
J 2
(-5988 5308);
DISPLAY 0.489362 (-5988 5308);
PAINT GREEN (-5988 5308);
FORCEPROP 2 LAST CDS_LIB mstr_standard
J 2
(-6050 5300);
DISPLAY 0.723404 (-6050 5300);
PAINT MONO (-6050 5300);
DISPLAY INVISIBLE (-6050 5300);
FORCEPROP 1 LAST BODY_TYPE PLUMBING
J 2
(-6050 5350);
DISPLAY 0.872340 (-6050 5350);
PAINT GREEN (-6050 5350);
DISPLAY INVISIBLE (-6050 5350);
FORCEPROP 1 LAST HDL_TAP TRUE
J 2
(-6375 5175);
DISPLAY 0.872340 (-6375 5175);
DISPLAY INVISIBLE (-6375 5175);
FORCEPROP 1 LAST PATH I269
J 2
(-6048 5300);
DISPLAY 0.872340 (-6048 5300);
PAINT GREEN (-6048 5300);
DISPLAY INVISIBLE (-6048 5300);
FORCEADD TAP..1
R 2
(-6050 5200);
FORCEPROP 3 LASTPIN (-6000 5200) SIG_NAME M_G_CPU1_SA_DQS_DN<8>
J 0
(-5990 5210);
DISPLAY 0.659574 (-5990 5210);
PAINT MONO (-5990 5210);
DISPLAY INVISIBLE (-5990 5210);
FORCEPROP 1 LASTPIN (-6000 5200) BN 8
J 2
(-5988 5208);
DISPLAY 0.489362 (-5988 5208);
PAINT GREEN (-5988 5208);
FORCEPROP 2 LAST CDS_LIB mstr_standard
J 2
(-6050 5200);
DISPLAY 0.723404 (-6050 5200);
PAINT MONO (-6050 5200);
DISPLAY INVISIBLE (-6050 5200);
FORCEPROP 1 LAST BODY_TYPE PLUMBING
J 2
(-6050 5250);
DISPLAY 0.872340 (-6050 5250);
PAINT GREEN (-6050 5250);
DISPLAY INVISIBLE (-6050 5250);
FORCEPROP 1 LAST HDL_TAP TRUE
J 2
(-6375 5075);
DISPLAY 0.872340 (-6375 5075);
DISPLAY INVISIBLE (-6375 5075);
FORCEPROP 1 LAST PATH I270
J 2
(-6048 5200);
DISPLAY 0.872340 (-6048 5200);
PAINT GREEN (-6048 5200);
DISPLAY INVISIBLE (-6048 5200);
FORCEADD TAP..1
R 2
(-5850 5000);
FORCEPROP 3 LASTPIN (-5800 5000) SIG_NAME M_G_CPU1_SB_DQS_DP<0>
J 0
(-5790 5010);
DISPLAY 0.659574 (-5790 5010);
PAINT MONO (-5790 5010);
DISPLAY INVISIBLE (-5790 5010);
FORCEPROP 1 LASTPIN (-5800 5000) BN 0
J 2
(-5788 5008);
DISPLAY 0.489362 (-5788 5008);
PAINT GREEN (-5788 5008);
FORCEPROP 2 LAST CDS_LIB mstr_standard
J 2
(-5850 5000);
DISPLAY 0.723404 (-5850 5000);
PAINT MONO (-5850 5000);
DISPLAY INVISIBLE (-5850 5000);
FORCEPROP 1 LAST BODY_TYPE PLUMBING
J 2
(-5850 5050);
DISPLAY 0.872340 (-5850 5050);
PAINT GREEN (-5850 5050);
DISPLAY INVISIBLE (-5850 5050);
FORCEPROP 1 LAST HDL_TAP TRUE
J 2
(-6175 4875);
DISPLAY 0.872340 (-6175 4875);
DISPLAY INVISIBLE (-6175 4875);
FORCEPROP 1 LAST PATH I271
J 2
(-5848 5000);
DISPLAY 0.872340 (-5848 5000);
PAINT GREEN (-5848 5000);
DISPLAY INVISIBLE (-5848 5000);
FORCEADD TAP..1
R 2
(-5850 4900);
FORCEPROP 3 LASTPIN (-5800 4900) SIG_NAME M_G_CPU1_SB_DQS_DP<1>
J 0
(-5790 4910);
DISPLAY 0.659574 (-5790 4910);
PAINT MONO (-5790 4910);
DISPLAY INVISIBLE (-5790 4910);
FORCEPROP 1 LASTPIN (-5800 4900) BN 1
J 2
(-5788 4908);
DISPLAY 0.489362 (-5788 4908);
PAINT GREEN (-5788 4908);
FORCEPROP 2 LAST CDS_LIB mstr_standard
J 2
(-5850 4900);
DISPLAY 0.723404 (-5850 4900);
PAINT MONO (-5850 4900);
DISPLAY INVISIBLE (-5850 4900);
FORCEPROP 1 LAST BODY_TYPE PLUMBING
J 2
(-5850 4950);
DISPLAY 0.872340 (-5850 4950);
PAINT GREEN (-5850 4950);
DISPLAY INVISIBLE (-5850 4950);
FORCEPROP 1 LAST HDL_TAP TRUE
J 2
(-6175 4775);
DISPLAY 0.872340 (-6175 4775);
DISPLAY INVISIBLE (-6175 4775);
FORCEPROP 1 LAST PATH I272
J 2
(-5848 4900);
DISPLAY 0.872340 (-5848 4900);
PAINT GREEN (-5848 4900);
DISPLAY INVISIBLE (-5848 4900);
FORCEADD TAP..1
R 2
(-5850 4800);
FORCEPROP 3 LASTPIN (-5800 4800) SIG_NAME M_G_CPU1_SB_DQS_DP<2>
J 0
(-5790 4810);
DISPLAY 0.659574 (-5790 4810);
PAINT MONO (-5790 4810);
DISPLAY INVISIBLE (-5790 4810);
FORCEPROP 1 LASTPIN (-5800 4800) BN 2
J 2
(-5788 4808);
DISPLAY 0.489362 (-5788 4808);
PAINT GREEN (-5788 4808);
FORCEPROP 2 LAST CDS_LIB mstr_standard
J 2
(-5850 4800);
DISPLAY 0.723404 (-5850 4800);
PAINT MONO (-5850 4800);
DISPLAY INVISIBLE (-5850 4800);
FORCEPROP 1 LAST BODY_TYPE PLUMBING
J 2
(-5850 4850);
DISPLAY 0.872340 (-5850 4850);
PAINT GREEN (-5850 4850);
DISPLAY INVISIBLE (-5850 4850);
FORCEPROP 1 LAST HDL_TAP TRUE
J 2
(-6175 4675);
DISPLAY 0.872340 (-6175 4675);
DISPLAY INVISIBLE (-6175 4675);
FORCEPROP 1 LAST PATH I273
J 2
(-5848 4800);
DISPLAY 0.872340 (-5848 4800);
PAINT GREEN (-5848 4800);
DISPLAY INVISIBLE (-5848 4800);
FORCEADD TAP..1
R 2
(-5850 4700);
FORCEPROP 3 LASTPIN (-5800 4700) SIG_NAME M_G_CPU1_SB_DQS_DP<3>
J 0
(-5790 4710);
DISPLAY 0.659574 (-5790 4710);
PAINT MONO (-5790 4710);
DISPLAY INVISIBLE (-5790 4710);
FORCEPROP 1 LASTPIN (-5800 4700) BN 3
J 2
(-5788 4708);
DISPLAY 0.489362 (-5788 4708);
PAINT GREEN (-5788 4708);
FORCEPROP 2 LAST CDS_LIB mstr_standard
J 2
(-5850 4700);
DISPLAY 0.723404 (-5850 4700);
PAINT MONO (-5850 4700);
DISPLAY INVISIBLE (-5850 4700);
FORCEPROP 1 LAST BODY_TYPE PLUMBING
J 2
(-5850 4750);
DISPLAY 0.872340 (-5850 4750);
PAINT GREEN (-5850 4750);
DISPLAY INVISIBLE (-5850 4750);
FORCEPROP 1 LAST HDL_TAP TRUE
J 2
(-6175 4575);
DISPLAY 0.872340 (-6175 4575);
DISPLAY INVISIBLE (-6175 4575);
FORCEPROP 1 LAST PATH I274
J 2
(-5848 4700);
DISPLAY 0.872340 (-5848 4700);
PAINT GREEN (-5848 4700);
DISPLAY INVISIBLE (-5848 4700);
FORCEADD TAP..1
R 2
(-6050 5100);
FORCEPROP 3 LASTPIN (-6000 5100) SIG_NAME M_G_CPU1_SA_DQS_DN<9>
J 0
(-5990 5110);
DISPLAY 0.659574 (-5990 5110);
PAINT MONO (-5990 5110);
DISPLAY INVISIBLE (-5990 5110);
FORCEPROP 1 LASTPIN (-6000 5100) BN 9
J 2
(-5988 5108);
DISPLAY 0.489362 (-5988 5108);
PAINT GREEN (-5988 5108);
FORCEPROP 2 LAST CDS_LIB mstr_standard
J 2
(-6050 5100);
DISPLAY 0.723404 (-6050 5100);
PAINT MONO (-6050 5100);
DISPLAY INVISIBLE (-6050 5100);
FORCEPROP 1 LAST BODY_TYPE PLUMBING
J 2
(-6050 5150);
DISPLAY 0.872340 (-6050 5150);
PAINT GREEN (-6050 5150);
DISPLAY INVISIBLE (-6050 5150);
FORCEPROP 1 LAST HDL_TAP TRUE
J 2
(-6375 4975);
DISPLAY 0.872340 (-6375 4975);
DISPLAY INVISIBLE (-6375 4975);
FORCEPROP 1 LAST PATH I275
J 2
(-6048 5100);
DISPLAY 0.872340 (-6048 5100);
PAINT GREEN (-6048 5100);
DISPLAY INVISIBLE (-6048 5100);
FORCEADD TAP..1
R 2
(-6050 4950);
FORCEPROP 3 LASTPIN (-6000 4950) SIG_NAME M_G_CPU1_SB_DQS_DN<0>
J 0
(-5990 4960);
DISPLAY 0.659574 (-5990 4960);
PAINT MONO (-5990 4960);
DISPLAY INVISIBLE (-5990 4960);
FORCEPROP 1 LASTPIN (-6000 4950) BN 0
J 2
(-5988 4958);
DISPLAY 0.489362 (-5988 4958);
PAINT GREEN (-5988 4958);
FORCEPROP 2 LAST CDS_LIB mstr_standard
J 2
(-6050 4950);
DISPLAY 0.723404 (-6050 4950);
PAINT MONO (-6050 4950);
DISPLAY INVISIBLE (-6050 4950);
FORCEPROP 1 LAST BODY_TYPE PLUMBING
J 2
(-6050 5000);
DISPLAY 0.872340 (-6050 5000);
PAINT GREEN (-6050 5000);
DISPLAY INVISIBLE (-6050 5000);
FORCEPROP 1 LAST HDL_TAP TRUE
J 2
(-6375 4825);
DISPLAY 0.872340 (-6375 4825);
DISPLAY INVISIBLE (-6375 4825);
FORCEPROP 1 LAST PATH I276
J 2
(-6048 4950);
DISPLAY 0.872340 (-6048 4950);
PAINT GREEN (-6048 4950);
DISPLAY INVISIBLE (-6048 4950);
FORCEADD TAP..1
R 2
(-6050 4850);
FORCEPROP 3 LASTPIN (-6000 4850) SIG_NAME M_G_CPU1_SB_DQS_DN<1>
J 0
(-5990 4860);
DISPLAY 0.659574 (-5990 4860);
PAINT MONO (-5990 4860);
DISPLAY INVISIBLE (-5990 4860);
FORCEPROP 1 LASTPIN (-6000 4850) BN 1
J 2
(-5988 4858);
DISPLAY 0.489362 (-5988 4858);
PAINT GREEN (-5988 4858);
FORCEPROP 2 LAST CDS_LIB mstr_standard
J 2
(-6050 4850);
DISPLAY 0.723404 (-6050 4850);
PAINT MONO (-6050 4850);
DISPLAY INVISIBLE (-6050 4850);
FORCEPROP 1 LAST BODY_TYPE PLUMBING
J 2
(-6050 4900);
DISPLAY 0.872340 (-6050 4900);
PAINT GREEN (-6050 4900);
DISPLAY INVISIBLE (-6050 4900);
FORCEPROP 1 LAST HDL_TAP TRUE
J 2
(-6375 4725);
DISPLAY 0.872340 (-6375 4725);
DISPLAY INVISIBLE (-6375 4725);
FORCEPROP 1 LAST PATH I277
J 2
(-6048 4850);
DISPLAY 0.872340 (-6048 4850);
PAINT GREEN (-6048 4850);
DISPLAY INVISIBLE (-6048 4850);
FORCEADD TAP..1
R 2
(-6050 4750);
FORCEPROP 3 LASTPIN (-6000 4750) SIG_NAME M_G_CPU1_SB_DQS_DN<2>
J 0
(-5990 4760);
DISPLAY 0.659574 (-5990 4760);
PAINT MONO (-5990 4760);
DISPLAY INVISIBLE (-5990 4760);
FORCEPROP 1 LASTPIN (-6000 4750) BN 2
J 2
(-5988 4758);
DISPLAY 0.489362 (-5988 4758);
PAINT GREEN (-5988 4758);
FORCEPROP 2 LAST CDS_LIB mstr_standard
J 2
(-6050 4750);
DISPLAY 0.723404 (-6050 4750);
PAINT MONO (-6050 4750);
DISPLAY INVISIBLE (-6050 4750);
FORCEPROP 1 LAST BODY_TYPE PLUMBING
J 2
(-6050 4800);
DISPLAY 0.872340 (-6050 4800);
PAINT GREEN (-6050 4800);
DISPLAY INVISIBLE (-6050 4800);
FORCEPROP 1 LAST HDL_TAP TRUE
J 2
(-6375 4625);
DISPLAY 0.872340 (-6375 4625);
DISPLAY INVISIBLE (-6375 4625);
FORCEPROP 1 LAST PATH I278
J 2
(-6048 4750);
DISPLAY 0.872340 (-6048 4750);
PAINT GREEN (-6048 4750);
DISPLAY INVISIBLE (-6048 4750);
FORCEADD TAP..1
R 2
(-6050 4650);
FORCEPROP 3 LASTPIN (-6000 4650) SIG_NAME M_G_CPU1_SB_DQS_DN<3>
J 0
(-5990 4660);
DISPLAY 0.659574 (-5990 4660);
PAINT MONO (-5990 4660);
DISPLAY INVISIBLE (-5990 4660);
FORCEPROP 1 LASTPIN (-6000 4650) BN 3
J 2
(-5988 4658);
DISPLAY 0.489362 (-5988 4658);
PAINT GREEN (-5988 4658);
FORCEPROP 2 LAST CDS_LIB mstr_standard
J 2
(-6050 4650);
DISPLAY 0.723404 (-6050 4650);
PAINT MONO (-6050 4650);
DISPLAY INVISIBLE (-6050 4650);
FORCEPROP 1 LAST BODY_TYPE PLUMBING
J 2
(-6050 4700);
DISPLAY 0.872340 (-6050 4700);
PAINT GREEN (-6050 4700);
DISPLAY INVISIBLE (-6050 4700);
FORCEPROP 1 LAST HDL_TAP TRUE
J 2
(-6375 4525);
DISPLAY 0.872340 (-6375 4525);
DISPLAY INVISIBLE (-6375 4525);
FORCEPROP 1 LAST PATH I279
J 2
(-6048 4650);
DISPLAY 0.872340 (-6048 4650);
PAINT GREEN (-6048 4650);
DISPLAY INVISIBLE (-6048 4650);
FORCEADD TAP..1
R 2
(-5850 4600);
FORCEPROP 3 LASTPIN (-5800 4600) SIG_NAME M_G_CPU1_SB_DQS_DP<4>
J 0
(-5790 4610);
DISPLAY 0.659574 (-5790 4610);
PAINT MONO (-5790 4610);
DISPLAY INVISIBLE (-5790 4610);
FORCEPROP 1 LASTPIN (-5800 4600) BN 4
J 2
(-5788 4608);
DISPLAY 0.489362 (-5788 4608);
PAINT GREEN (-5788 4608);
FORCEPROP 2 LAST CDS_LIB mstr_standard
J 2
(-5850 4600);
DISPLAY 0.723404 (-5850 4600);
PAINT MONO (-5850 4600);
DISPLAY INVISIBLE (-5850 4600);
FORCEPROP 1 LAST BODY_TYPE PLUMBING
J 2
(-5850 4650);
DISPLAY 0.872340 (-5850 4650);
PAINT GREEN (-5850 4650);
DISPLAY INVISIBLE (-5850 4650);
FORCEPROP 1 LAST HDL_TAP TRUE
J 2
(-6175 4475);
DISPLAY 0.872340 (-6175 4475);
DISPLAY INVISIBLE (-6175 4475);
FORCEPROP 1 LAST PATH I280
J 2
(-5848 4600);
DISPLAY 0.872340 (-5848 4600);
PAINT GREEN (-5848 4600);
DISPLAY INVISIBLE (-5848 4600);
FORCEADD TAP..1
R 2
(-5850 4500);
FORCEPROP 3 LASTPIN (-5800 4500) SIG_NAME M_G_CPU1_SB_DQS_DP<5>
J 0
(-5790 4510);
DISPLAY 0.659574 (-5790 4510);
PAINT MONO (-5790 4510);
DISPLAY INVISIBLE (-5790 4510);
FORCEPROP 1 LASTPIN (-5800 4500) BN 5
J 2
(-5788 4508);
DISPLAY 0.489362 (-5788 4508);
PAINT GREEN (-5788 4508);
FORCEPROP 2 LAST CDS_LIB mstr_standard
J 2
(-5850 4500);
DISPLAY 0.723404 (-5850 4500);
PAINT MONO (-5850 4500);
DISPLAY INVISIBLE (-5850 4500);
FORCEPROP 1 LAST BODY_TYPE PLUMBING
J 2
(-5850 4550);
DISPLAY 0.872340 (-5850 4550);
PAINT GREEN (-5850 4550);
DISPLAY INVISIBLE (-5850 4550);
FORCEPROP 1 LAST HDL_TAP TRUE
J 2
(-6175 4375);
DISPLAY 0.872340 (-6175 4375);
DISPLAY INVISIBLE (-6175 4375);
FORCEPROP 1 LAST PATH I281
J 2
(-5848 4500);
DISPLAY 0.872340 (-5848 4500);
PAINT GREEN (-5848 4500);
DISPLAY INVISIBLE (-5848 4500);
FORCEADD TAP..1
R 2
(-5850 4400);
FORCEPROP 3 LASTPIN (-5800 4400) SIG_NAME M_G_CPU1_SB_DQS_DP<6>
J 0
(-5790 4410);
DISPLAY 0.659574 (-5790 4410);
PAINT MONO (-5790 4410);
DISPLAY INVISIBLE (-5790 4410);
FORCEPROP 1 LASTPIN (-5800 4400) BN 6
J 2
(-5788 4408);
DISPLAY 0.489362 (-5788 4408);
PAINT GREEN (-5788 4408);
FORCEPROP 2 LAST CDS_LIB mstr_standard
J 2
(-5850 4400);
DISPLAY 0.723404 (-5850 4400);
PAINT MONO (-5850 4400);
DISPLAY INVISIBLE (-5850 4400);
FORCEPROP 1 LAST BODY_TYPE PLUMBING
J 2
(-5850 4450);
DISPLAY 0.872340 (-5850 4450);
PAINT GREEN (-5850 4450);
DISPLAY INVISIBLE (-5850 4450);
FORCEPROP 1 LAST HDL_TAP TRUE
J 2
(-6175 4275);
DISPLAY 0.872340 (-6175 4275);
DISPLAY INVISIBLE (-6175 4275);
FORCEPROP 1 LAST PATH I282
J 2
(-5848 4400);
DISPLAY 0.872340 (-5848 4400);
PAINT GREEN (-5848 4400);
DISPLAY INVISIBLE (-5848 4400);
FORCEADD TAP..1
R 2
(-5850 4300);
FORCEPROP 3 LASTPIN (-5800 4300) SIG_NAME M_G_CPU1_SB_DQS_DP<7>
J 0
(-5790 4310);
DISPLAY 0.659574 (-5790 4310);
PAINT MONO (-5790 4310);
DISPLAY INVISIBLE (-5790 4310);
FORCEPROP 1 LASTPIN (-5800 4300) BN 7
J 2
(-5788 4308);
DISPLAY 0.489362 (-5788 4308);
PAINT GREEN (-5788 4308);
FORCEPROP 2 LAST CDS_LIB mstr_standard
J 2
(-5850 4300);
DISPLAY 0.723404 (-5850 4300);
PAINT MONO (-5850 4300);
DISPLAY INVISIBLE (-5850 4300);
FORCEPROP 1 LAST BODY_TYPE PLUMBING
J 2
(-5850 4350);
DISPLAY 0.872340 (-5850 4350);
PAINT GREEN (-5850 4350);
DISPLAY INVISIBLE (-5850 4350);
FORCEPROP 1 LAST HDL_TAP TRUE
J 2
(-6175 4175);
DISPLAY 0.872340 (-6175 4175);
DISPLAY INVISIBLE (-6175 4175);
FORCEPROP 1 LAST PATH I283
J 2
(-5848 4300);
DISPLAY 0.872340 (-5848 4300);
PAINT GREEN (-5848 4300);
DISPLAY INVISIBLE (-5848 4300);
FORCEADD TAP..1
R 2
(-5850 4200);
FORCEPROP 3 LASTPIN (-5800 4200) SIG_NAME M_G_CPU1_SB_DQS_DP<8>
J 0
(-5790 4210);
DISPLAY 0.659574 (-5790 4210);
PAINT MONO (-5790 4210);
DISPLAY INVISIBLE (-5790 4210);
FORCEPROP 1 LASTPIN (-5800 4200) BN 8
J 2
(-5788 4208);
DISPLAY 0.489362 (-5788 4208);
PAINT GREEN (-5788 4208);
FORCEPROP 2 LAST CDS_LIB mstr_standard
J 2
(-5850 4200);
DISPLAY 0.723404 (-5850 4200);
PAINT MONO (-5850 4200);
DISPLAY INVISIBLE (-5850 4200);
FORCEPROP 1 LAST BODY_TYPE PLUMBING
J 2
(-5850 4250);
DISPLAY 0.872340 (-5850 4250);
PAINT GREEN (-5850 4250);
DISPLAY INVISIBLE (-5850 4250);
FORCEPROP 1 LAST HDL_TAP TRUE
J 2
(-6175 4075);
DISPLAY 0.872340 (-6175 4075);
DISPLAY INVISIBLE (-6175 4075);
FORCEPROP 1 LAST PATH I284
J 2
(-5848 4200);
DISPLAY 0.872340 (-5848 4200);
PAINT GREEN (-5848 4200);
DISPLAY INVISIBLE (-5848 4200);
FORCEADD TAP..1
R 2
(-5850 4100);
FORCEPROP 3 LASTPIN (-5800 4100) SIG_NAME M_G_CPU1_SB_DQS_DP<9>
J 0
(-5790 4110);
DISPLAY 0.659574 (-5790 4110);
PAINT MONO (-5790 4110);
DISPLAY INVISIBLE (-5790 4110);
FORCEPROP 1 LASTPIN (-5800 4100) BN 9
J 2
(-5788 4108);
DISPLAY 0.489362 (-5788 4108);
PAINT GREEN (-5788 4108);
FORCEPROP 2 LAST CDS_LIB mstr_standard
J 2
(-5850 4100);
DISPLAY 0.723404 (-5850 4100);
PAINT MONO (-5850 4100);
DISPLAY INVISIBLE (-5850 4100);
FORCEPROP 1 LAST BODY_TYPE PLUMBING
J 2
(-5850 4150);
DISPLAY 0.872340 (-5850 4150);
PAINT GREEN (-5850 4150);
DISPLAY INVISIBLE (-5850 4150);
FORCEPROP 1 LAST HDL_TAP TRUE
J 2
(-6175 3975);
DISPLAY 0.872340 (-6175 3975);
DISPLAY INVISIBLE (-6175 3975);
FORCEPROP 1 LAST PATH I285
J 2
(-5848 4100);
DISPLAY 0.872340 (-5848 4100);
PAINT GREEN (-5848 4100);
DISPLAY INVISIBLE (-5848 4100);
FORCEADD TAP..1
R 2
(-6050 4550);
FORCEPROP 3 LASTPIN (-6000 4550) SIG_NAME M_G_CPU1_SB_DQS_DN<4>
J 0
(-5990 4560);
DISPLAY 0.659574 (-5990 4560);
PAINT MONO (-5990 4560);
DISPLAY INVISIBLE (-5990 4560);
FORCEPROP 1 LASTPIN (-6000 4550) BN 4
J 2
(-5988 4558);
DISPLAY 0.489362 (-5988 4558);
PAINT GREEN (-5988 4558);
FORCEPROP 2 LAST CDS_LIB mstr_standard
J 2
(-6050 4550);
DISPLAY 0.723404 (-6050 4550);
PAINT MONO (-6050 4550);
DISPLAY INVISIBLE (-6050 4550);
FORCEPROP 1 LAST BODY_TYPE PLUMBING
J 2
(-6050 4600);
DISPLAY 0.872340 (-6050 4600);
PAINT GREEN (-6050 4600);
DISPLAY INVISIBLE (-6050 4600);
FORCEPROP 1 LAST HDL_TAP TRUE
J 2
(-6375 4425);
DISPLAY 0.872340 (-6375 4425);
DISPLAY INVISIBLE (-6375 4425);
FORCEPROP 1 LAST PATH I286
J 2
(-6048 4550);
DISPLAY 0.872340 (-6048 4550);
PAINT GREEN (-6048 4550);
DISPLAY INVISIBLE (-6048 4550);
FORCEADD TAP..1
R 2
(-6050 4450);
FORCEPROP 3 LASTPIN (-6000 4450) SIG_NAME M_G_CPU1_SB_DQS_DN<5>
J 0
(-5990 4460);
DISPLAY 0.659574 (-5990 4460);
PAINT MONO (-5990 4460);
DISPLAY INVISIBLE (-5990 4460);
FORCEPROP 1 LASTPIN (-6000 4450) BN 5
J 2
(-5988 4458);
DISPLAY 0.489362 (-5988 4458);
PAINT GREEN (-5988 4458);
FORCEPROP 2 LAST CDS_LIB mstr_standard
J 2
(-6050 4450);
DISPLAY 0.723404 (-6050 4450);
PAINT MONO (-6050 4450);
DISPLAY INVISIBLE (-6050 4450);
FORCEPROP 1 LAST BODY_TYPE PLUMBING
J 2
(-6050 4500);
DISPLAY 0.872340 (-6050 4500);
PAINT GREEN (-6050 4500);
DISPLAY INVISIBLE (-6050 4500);
FORCEPROP 1 LAST HDL_TAP TRUE
J 2
(-6375 4325);
DISPLAY 0.872340 (-6375 4325);
DISPLAY INVISIBLE (-6375 4325);
FORCEPROP 1 LAST PATH I287
J 2
(-6048 4450);
DISPLAY 0.872340 (-6048 4450);
PAINT GREEN (-6048 4450);
DISPLAY INVISIBLE (-6048 4450);
FORCEADD TAP..1
R 2
(-6050 4350);
FORCEPROP 3 LASTPIN (-6000 4350) SIG_NAME M_G_CPU1_SB_DQS_DN<6>
J 0
(-5990 4360);
DISPLAY 0.659574 (-5990 4360);
PAINT MONO (-5990 4360);
DISPLAY INVISIBLE (-5990 4360);
FORCEPROP 1 LASTPIN (-6000 4350) BN 6
J 2
(-5988 4358);
DISPLAY 0.489362 (-5988 4358);
PAINT GREEN (-5988 4358);
FORCEPROP 2 LAST CDS_LIB mstr_standard
J 2
(-6050 4350);
DISPLAY 0.723404 (-6050 4350);
PAINT MONO (-6050 4350);
DISPLAY INVISIBLE (-6050 4350);
FORCEPROP 1 LAST BODY_TYPE PLUMBING
J 2
(-6050 4400);
DISPLAY 0.872340 (-6050 4400);
PAINT GREEN (-6050 4400);
DISPLAY INVISIBLE (-6050 4400);
FORCEPROP 1 LAST HDL_TAP TRUE
J 2
(-6375 4225);
DISPLAY 0.872340 (-6375 4225);
DISPLAY INVISIBLE (-6375 4225);
FORCEPROP 1 LAST PATH I288
J 2
(-6048 4350);
DISPLAY 0.872340 (-6048 4350);
PAINT GREEN (-6048 4350);
DISPLAY INVISIBLE (-6048 4350);
FORCEADD TAP..1
R 2
(-6050 4250);
FORCEPROP 3 LASTPIN (-6000 4250) SIG_NAME M_G_CPU1_SB_DQS_DN<7>
J 0
(-5990 4260);
DISPLAY 0.659574 (-5990 4260);
PAINT MONO (-5990 4260);
DISPLAY INVISIBLE (-5990 4260);
FORCEPROP 1 LASTPIN (-6000 4250) BN 7
J 2
(-5988 4258);
DISPLAY 0.489362 (-5988 4258);
PAINT GREEN (-5988 4258);
FORCEPROP 2 LAST CDS_LIB mstr_standard
J 2
(-6050 4250);
DISPLAY 0.723404 (-6050 4250);
PAINT MONO (-6050 4250);
DISPLAY INVISIBLE (-6050 4250);
FORCEPROP 1 LAST BODY_TYPE PLUMBING
J 2
(-6050 4300);
DISPLAY 0.872340 (-6050 4300);
PAINT GREEN (-6050 4300);
DISPLAY INVISIBLE (-6050 4300);
FORCEPROP 1 LAST HDL_TAP TRUE
J 2
(-6375 4125);
DISPLAY 0.872340 (-6375 4125);
DISPLAY INVISIBLE (-6375 4125);
FORCEPROP 1 LAST PATH I289
J 2
(-6048 4250);
DISPLAY 0.872340 (-6048 4250);
PAINT GREEN (-6048 4250);
DISPLAY INVISIBLE (-6048 4250);
FORCEADD TAP..1
R 2
(-6050 4150);
FORCEPROP 3 LASTPIN (-6000 4150) SIG_NAME M_G_CPU1_SB_DQS_DN<8>
J 0
(-5990 4160);
DISPLAY 0.659574 (-5990 4160);
PAINT MONO (-5990 4160);
DISPLAY INVISIBLE (-5990 4160);
FORCEPROP 1 LASTPIN (-6000 4150) BN 8
J 2
(-5988 4158);
DISPLAY 0.489362 (-5988 4158);
PAINT GREEN (-5988 4158);
FORCEPROP 2 LAST CDS_LIB mstr_standard
J 2
(-6050 4150);
DISPLAY 0.723404 (-6050 4150);
PAINT MONO (-6050 4150);
DISPLAY INVISIBLE (-6050 4150);
FORCEPROP 1 LAST BODY_TYPE PLUMBING
J 2
(-6050 4200);
DISPLAY 0.872340 (-6050 4200);
PAINT GREEN (-6050 4200);
DISPLAY INVISIBLE (-6050 4200);
FORCEPROP 1 LAST HDL_TAP TRUE
J 2
(-6375 4025);
DISPLAY 0.872340 (-6375 4025);
DISPLAY INVISIBLE (-6375 4025);
FORCEPROP 1 LAST PATH I290
J 2
(-6048 4150);
DISPLAY 0.872340 (-6048 4150);
PAINT GREEN (-6048 4150);
DISPLAY INVISIBLE (-6048 4150);
FORCEADD OFFPAGE..3
R 2
(-6750 6025);
FORCEPROP 2 LAST $XR0 104 
J 0
(-7030 6025);
DISPLAY 0.638298 (-7030 6025);
PAINT MONO (-7030 6025);
FORCEPROP 2 LAST CDS_LIB standard
J 0
(-6750 6025);
DISPLAY INVISIBLE (-6750 6025);
FORCEPROP 1 LAST OFFPAGE TRUE
J 2
(-7075 5900);
DISPLAY 0.872340 (-7075 5900);
PAINT GREEN (-7075 5900);
DISPLAY INVISIBLE (-7075 5900);
FORCEPROP 1 LAST COMMENT_BODY TRUE
J 2
(-6700 5925);
DISPLAY 0.872340 (-6700 5925);
PAINT GREEN (-6700 5925);
DISPLAY INVISIBLE (-6700 5925);
FORCEPROP 2 LAST PATH I291
J 0
(-7025 6075);
DISPLAY 1.021277 (-7025 6075);
DISPLAY INVISIBLE (-7025 6075);
FORCEADD OFFPAGE..3
R 2
(-6750 6075);
FORCEPROP 2 LAST $XR0 104 
J 0
(-7030 6075);
DISPLAY 0.638298 (-7030 6075);
PAINT MONO (-7030 6075);
FORCEPROP 2 LAST CDS_LIB standard
J 0
(-6750 6075);
DISPLAY INVISIBLE (-6750 6075);
FORCEPROP 1 LAST OFFPAGE TRUE
J 2
(-7075 5950);
DISPLAY 0.872340 (-7075 5950);
PAINT GREEN (-7075 5950);
DISPLAY INVISIBLE (-7075 5950);
FORCEPROP 1 LAST COMMENT_BODY TRUE
J 2
(-6700 5975);
DISPLAY 0.872340 (-6700 5975);
PAINT GREEN (-6700 5975);
DISPLAY INVISIBLE (-6700 5975);
FORCEPROP 2 LAST PATH I292
J 0
(-7025 6125);
DISPLAY 1.021277 (-7025 6125);
DISPLAY INVISIBLE (-7025 6125);
FORCEADD OFFPAGE..3
R 2
(-6750 4975);
FORCEPROP 2 LAST $XR0 104 
J 0
(-7030 4975);
DISPLAY 0.638298 (-7030 4975);
PAINT MONO (-7030 4975);
FORCEPROP 2 LAST CDS_LIB standard
J 0
(-6750 4975);
DISPLAY INVISIBLE (-6750 4975);
FORCEPROP 1 LAST OFFPAGE TRUE
J 2
(-7075 4850);
DISPLAY 0.872340 (-7075 4850);
PAINT GREEN (-7075 4850);
DISPLAY INVISIBLE (-7075 4850);
FORCEPROP 1 LAST COMMENT_BODY TRUE
J 2
(-6700 4875);
DISPLAY 0.872340 (-6700 4875);
PAINT GREEN (-6700 4875);
DISPLAY INVISIBLE (-6700 4875);
FORCEPROP 2 LAST PATH I293
J 0
(-7025 5025);
DISPLAY 1.021277 (-7025 5025);
DISPLAY INVISIBLE (-7025 5025);
FORCEADD OFFPAGE..3
R 2
(-6750 5025);
FORCEPROP 2 LAST $XR0 104 
J 0
(-7030 5025);
DISPLAY 0.638298 (-7030 5025);
PAINT MONO (-7030 5025);
FORCEPROP 2 LAST CDS_LIB standard
J 0
(-6750 5025);
DISPLAY INVISIBLE (-6750 5025);
FORCEPROP 1 LAST OFFPAGE TRUE
J 2
(-7075 4900);
DISPLAY 0.872340 (-7075 4900);
PAINT GREEN (-7075 4900);
DISPLAY INVISIBLE (-7075 4900);
FORCEPROP 1 LAST COMMENT_BODY TRUE
J 2
(-6700 4925);
DISPLAY 0.872340 (-6700 4925);
PAINT GREEN (-6700 4925);
DISPLAY INVISIBLE (-6700 4925);
FORCEPROP 2 LAST PATH I294
J 0
(-7025 5075);
DISPLAY 1.021277 (-7025 5075);
DISPLAY INVISIBLE (-7025 5075);
FORCEADD TAP..1
R 2
(-6050 4050);
FORCEPROP 3 LASTPIN (-6000 4050) SIG_NAME M_G_CPU1_SB_DQS_DN<9>
J 0
(-5990 4060);
DISPLAY 0.659574 (-5990 4060);
PAINT MONO (-5990 4060);
DISPLAY INVISIBLE (-5990 4060);
FORCEPROP 1 LASTPIN (-6000 4050) BN 9
J 2
(-5988 4058);
DISPLAY 0.489362 (-5988 4058);
PAINT GREEN (-5988 4058);
FORCEPROP 2 LAST CDS_LIB mstr_standard
J 2
(-6050 4050);
DISPLAY 0.723404 (-6050 4050);
PAINT MONO (-6050 4050);
DISPLAY INVISIBLE (-6050 4050);
FORCEPROP 1 LAST BODY_TYPE PLUMBING
J 2
(-6050 4100);
DISPLAY 0.872340 (-6050 4100);
PAINT GREEN (-6050 4100);
DISPLAY INVISIBLE (-6050 4100);
FORCEPROP 1 LAST HDL_TAP TRUE
J 2
(-6375 3925);
DISPLAY 0.872340 (-6375 3925);
DISPLAY INVISIBLE (-6375 3925);
FORCEPROP 1 LAST PATH I295
J 2
(-6048 4050);
DISPLAY 0.872340 (-6048 4050);
PAINT GREEN (-6048 4050);
DISPLAY INVISIBLE (-6048 4050);
FORCEADD TAP..1
R 2
(-6050 3900);
FORCEPROP 3 LASTPIN (-6000 3900) SIG_NAME M_G_CPU1_SA_CA<0>
J 0
(-5990 3910);
DISPLAY 0.659574 (-5990 3910);
PAINT MONO (-5990 3910);
DISPLAY INVISIBLE (-5990 3910);
FORCEPROP 1 LASTPIN (-6000 3900) BN 0
J 2
(-5988 3908);
DISPLAY 0.489362 (-5988 3908);
PAINT GREEN (-5988 3908);
FORCEPROP 2 LAST CDS_LIB mstr_standard
J 0
(-6050 3900);
DISPLAY 0.723404 (-6050 3900);
PAINT MONO (-6050 3900);
DISPLAY INVISIBLE (-6050 3900);
FORCEPROP 1 LAST BODY_TYPE PLUMBING
J 2
(-6050 3950);
DISPLAY 0.872340 (-6050 3950);
PAINT GREEN (-6050 3950);
DISPLAY INVISIBLE (-6050 3950);
FORCEPROP 1 LAST HDL_TAP TRUE
J 2
(-6375 3775);
DISPLAY 0.872340 (-6375 3775);
DISPLAY INVISIBLE (-6375 3775);
FORCEPROP 1 LAST PATH I296
J 2
(-6048 3900);
DISPLAY 0.872340 (-6048 3900);
PAINT GREEN (-6048 3900);
DISPLAY INVISIBLE (-6048 3900);
FORCEADD TAP..1
R 2
(-6050 3850);
FORCEPROP 3 LASTPIN (-6000 3850) SIG_NAME M_G_CPU1_SA_CA<1>
J 0
(-5990 3860);
DISPLAY 0.659574 (-5990 3860);
PAINT MONO (-5990 3860);
DISPLAY INVISIBLE (-5990 3860);
FORCEPROP 1 LASTPIN (-6000 3850) BN 1
J 2
(-5988 3858);
DISPLAY 0.489362 (-5988 3858);
PAINT GREEN (-5988 3858);
FORCEPROP 2 LAST CDS_LIB mstr_standard
J 0
(-6050 3850);
DISPLAY 0.723404 (-6050 3850);
PAINT MONO (-6050 3850);
DISPLAY INVISIBLE (-6050 3850);
FORCEPROP 1 LAST BODY_TYPE PLUMBING
J 2
(-6050 3900);
DISPLAY 0.872340 (-6050 3900);
PAINT GREEN (-6050 3900);
DISPLAY INVISIBLE (-6050 3900);
FORCEPROP 1 LAST HDL_TAP TRUE
J 2
(-6375 3725);
DISPLAY 0.872340 (-6375 3725);
DISPLAY INVISIBLE (-6375 3725);
FORCEPROP 1 LAST PATH I297
J 2
(-6048 3850);
DISPLAY 0.872340 (-6048 3850);
PAINT GREEN (-6048 3850);
DISPLAY INVISIBLE (-6048 3850);
FORCEADD TAP..1
R 2
(-6050 3800);
FORCEPROP 3 LASTPIN (-6000 3800) SIG_NAME M_G_CPU1_SA_CA<2>
J 0
(-5990 3810);
DISPLAY 0.659574 (-5990 3810);
PAINT MONO (-5990 3810);
DISPLAY INVISIBLE (-5990 3810);
FORCEPROP 1 LASTPIN (-6000 3800) BN 2
J 2
(-5988 3808);
DISPLAY 0.489362 (-5988 3808);
PAINT GREEN (-5988 3808);
FORCEPROP 2 LAST CDS_LIB mstr_standard
J 0
(-6050 3800);
DISPLAY 0.723404 (-6050 3800);
PAINT MONO (-6050 3800);
DISPLAY INVISIBLE (-6050 3800);
FORCEPROP 1 LAST BODY_TYPE PLUMBING
J 2
(-6050 3850);
DISPLAY 0.872340 (-6050 3850);
PAINT GREEN (-6050 3850);
DISPLAY INVISIBLE (-6050 3850);
FORCEPROP 1 LAST HDL_TAP TRUE
J 2
(-6375 3675);
DISPLAY 0.872340 (-6375 3675);
DISPLAY INVISIBLE (-6375 3675);
FORCEPROP 1 LAST PATH I298
J 2
(-6048 3800);
DISPLAY 0.872340 (-6048 3800);
PAINT GREEN (-6048 3800);
DISPLAY INVISIBLE (-6048 3800);
FORCEADD TAP..1
R 2
(-6050 3750);
FORCEPROP 3 LASTPIN (-6000 3750) SIG_NAME M_G_CPU1_SA_CA<3>
J 0
(-5990 3760);
DISPLAY 0.659574 (-5990 3760);
PAINT MONO (-5990 3760);
DISPLAY INVISIBLE (-5990 3760);
FORCEPROP 1 LASTPIN (-6000 3750) BN 3
J 2
(-5988 3758);
DISPLAY 0.489362 (-5988 3758);
PAINT GREEN (-5988 3758);
FORCEPROP 2 LAST CDS_LIB mstr_standard
J 0
(-6050 3750);
DISPLAY 0.723404 (-6050 3750);
PAINT MONO (-6050 3750);
DISPLAY INVISIBLE (-6050 3750);
FORCEPROP 1 LAST BODY_TYPE PLUMBING
J 2
(-6050 3800);
DISPLAY 0.872340 (-6050 3800);
PAINT GREEN (-6050 3800);
DISPLAY INVISIBLE (-6050 3800);
FORCEPROP 1 LAST HDL_TAP TRUE
J 2
(-6375 3625);
DISPLAY 0.872340 (-6375 3625);
DISPLAY INVISIBLE (-6375 3625);
FORCEPROP 1 LAST PATH I299
J 2
(-6048 3750);
DISPLAY 0.872340 (-6048 3750);
PAINT GREEN (-6048 3750);
DISPLAY INVISIBLE (-6048 3750);
FORCEADD TAP..1
R 2
(-6050 3700);
FORCEPROP 3 LASTPIN (-6000 3700) SIG_NAME M_G_CPU1_SA_CA<4>
J 0
(-5990 3710);
DISPLAY 0.659574 (-5990 3710);
PAINT MONO (-5990 3710);
DISPLAY INVISIBLE (-5990 3710);
FORCEPROP 1 LASTPIN (-6000 3700) BN 4
J 2
(-5988 3708);
DISPLAY 0.489362 (-5988 3708);
PAINT GREEN (-5988 3708);
FORCEPROP 2 LAST CDS_LIB mstr_standard
J 0
(-6050 3700);
DISPLAY 0.723404 (-6050 3700);
PAINT MONO (-6050 3700);
DISPLAY INVISIBLE (-6050 3700);
FORCEPROP 1 LAST BODY_TYPE PLUMBING
J 2
(-6050 3750);
DISPLAY 0.872340 (-6050 3750);
PAINT GREEN (-6050 3750);
DISPLAY INVISIBLE (-6050 3750);
FORCEPROP 1 LAST HDL_TAP TRUE
J 2
(-6375 3575);
DISPLAY 0.872340 (-6375 3575);
DISPLAY INVISIBLE (-6375 3575);
FORCEPROP 1 LAST PATH I300
J 2
(-6048 3700);
DISPLAY 0.872340 (-6048 3700);
PAINT GREEN (-6048 3700);
DISPLAY INVISIBLE (-6048 3700);
FORCEADD TAP..1
R 2
(-6050 3650);
FORCEPROP 3 LASTPIN (-6000 3650) SIG_NAME M_G_CPU1_SA_CA<5>
J 0
(-5990 3660);
DISPLAY 0.659574 (-5990 3660);
PAINT MONO (-5990 3660);
DISPLAY INVISIBLE (-5990 3660);
FORCEPROP 1 LASTPIN (-6000 3650) BN 5
J 2
(-5988 3658);
DISPLAY 0.489362 (-5988 3658);
PAINT GREEN (-5988 3658);
FORCEPROP 2 LAST CDS_LIB mstr_standard
J 0
(-6050 3650);
DISPLAY 0.723404 (-6050 3650);
PAINT MONO (-6050 3650);
DISPLAY INVISIBLE (-6050 3650);
FORCEPROP 1 LAST BODY_TYPE PLUMBING
J 2
(-6050 3700);
DISPLAY 0.872340 (-6050 3700);
PAINT GREEN (-6050 3700);
DISPLAY INVISIBLE (-6050 3700);
FORCEPROP 1 LAST HDL_TAP TRUE
J 2
(-6375 3525);
DISPLAY 0.872340 (-6375 3525);
DISPLAY INVISIBLE (-6375 3525);
FORCEPROP 1 LAST PATH I301
J 2
(-6048 3650);
DISPLAY 0.872340 (-6048 3650);
PAINT GREEN (-6048 3650);
DISPLAY INVISIBLE (-6048 3650);
FORCEADD TAP..1
R 2
(-6050 3600);
FORCEPROP 3 LASTPIN (-6000 3600) SIG_NAME M_G_CPU1_SA_CA<6>
J 0
(-5990 3610);
DISPLAY 0.659574 (-5990 3610);
PAINT MONO (-5990 3610);
DISPLAY INVISIBLE (-5990 3610);
FORCEPROP 1 LASTPIN (-6000 3600) BN 6
J 2
(-5988 3608);
DISPLAY 0.489362 (-5988 3608);
PAINT GREEN (-5988 3608);
FORCEPROP 2 LAST CDS_LIB mstr_standard
J 0
(-6050 3600);
DISPLAY 0.723404 (-6050 3600);
PAINT MONO (-6050 3600);
DISPLAY INVISIBLE (-6050 3600);
FORCEPROP 1 LAST BODY_TYPE PLUMBING
J 2
(-6050 3650);
DISPLAY 0.872340 (-6050 3650);
PAINT GREEN (-6050 3650);
DISPLAY INVISIBLE (-6050 3650);
FORCEPROP 1 LAST HDL_TAP TRUE
J 2
(-6375 3475);
DISPLAY 0.872340 (-6375 3475);
DISPLAY INVISIBLE (-6375 3475);
FORCEPROP 1 LAST PATH I302
J 2
(-6048 3600);
DISPLAY 0.872340 (-6048 3600);
PAINT GREEN (-6048 3600);
DISPLAY INVISIBLE (-6048 3600);
FORCEADD TAP..1
R 2
(-6050 3500);
FORCEPROP 3 LASTPIN (-6000 3500) SIG_NAME M_G_CPU1_SB_CA<0>
J 0
(-5990 3510);
DISPLAY 0.659574 (-5990 3510);
PAINT MONO (-5990 3510);
DISPLAY INVISIBLE (-5990 3510);
FORCEPROP 1 LASTPIN (-6000 3500) BN 0
J 2
(-5988 3508);
DISPLAY 0.489362 (-5988 3508);
PAINT GREEN (-5988 3508);
FORCEPROP 2 LAST CDS_LIB mstr_standard
J 0
(-6050 3500);
DISPLAY 0.723404 (-6050 3500);
PAINT MONO (-6050 3500);
DISPLAY INVISIBLE (-6050 3500);
FORCEPROP 1 LAST BODY_TYPE PLUMBING
J 2
(-6050 3550);
DISPLAY 0.872340 (-6050 3550);
PAINT GREEN (-6050 3550);
DISPLAY INVISIBLE (-6050 3550);
FORCEPROP 1 LAST HDL_TAP TRUE
J 2
(-6375 3375);
DISPLAY 0.872340 (-6375 3375);
DISPLAY INVISIBLE (-6375 3375);
FORCEPROP 1 LAST PATH I303
J 2
(-6048 3500);
DISPLAY 0.872340 (-6048 3500);
PAINT GREEN (-6048 3500);
DISPLAY INVISIBLE (-6048 3500);
FORCEADD TAP..1
R 2
(-6050 3450);
FORCEPROP 3 LASTPIN (-6000 3450) SIG_NAME M_G_CPU1_SB_CA<1>
J 0
(-5990 3460);
DISPLAY 0.659574 (-5990 3460);
PAINT MONO (-5990 3460);
DISPLAY INVISIBLE (-5990 3460);
FORCEPROP 1 LASTPIN (-6000 3450) BN 1
J 2
(-5988 3458);
DISPLAY 0.489362 (-5988 3458);
PAINT GREEN (-5988 3458);
FORCEPROP 2 LAST CDS_LIB mstr_standard
J 0
(-6050 3450);
DISPLAY 0.723404 (-6050 3450);
PAINT MONO (-6050 3450);
DISPLAY INVISIBLE (-6050 3450);
FORCEPROP 1 LAST BODY_TYPE PLUMBING
J 2
(-6050 3500);
DISPLAY 0.872340 (-6050 3500);
PAINT GREEN (-6050 3500);
DISPLAY INVISIBLE (-6050 3500);
FORCEPROP 1 LAST HDL_TAP TRUE
J 2
(-6375 3325);
DISPLAY 0.872340 (-6375 3325);
DISPLAY INVISIBLE (-6375 3325);
FORCEPROP 1 LAST PATH I304
J 2
(-6048 3450);
DISPLAY 0.872340 (-6048 3450);
PAINT GREEN (-6048 3450);
DISPLAY INVISIBLE (-6048 3450);
FORCEADD TAP..1
R 2
(-6050 3400);
FORCEPROP 3 LASTPIN (-6000 3400) SIG_NAME M_G_CPU1_SB_CA<2>
J 0
(-5990 3410);
DISPLAY 0.659574 (-5990 3410);
PAINT MONO (-5990 3410);
DISPLAY INVISIBLE (-5990 3410);
FORCEPROP 1 LASTPIN (-6000 3400) BN 2
J 2
(-5988 3408);
DISPLAY 0.489362 (-5988 3408);
PAINT GREEN (-5988 3408);
FORCEPROP 2 LAST CDS_LIB mstr_standard
J 0
(-6050 3400);
DISPLAY 0.723404 (-6050 3400);
PAINT MONO (-6050 3400);
DISPLAY INVISIBLE (-6050 3400);
FORCEPROP 1 LAST BODY_TYPE PLUMBING
J 2
(-6050 3450);
DISPLAY 0.872340 (-6050 3450);
PAINT GREEN (-6050 3450);
DISPLAY INVISIBLE (-6050 3450);
FORCEPROP 1 LAST HDL_TAP TRUE
J 2
(-6375 3275);
DISPLAY 0.872340 (-6375 3275);
DISPLAY INVISIBLE (-6375 3275);
FORCEPROP 1 LAST PATH I305
J 2
(-6048 3400);
DISPLAY 0.872340 (-6048 3400);
PAINT GREEN (-6048 3400);
DISPLAY INVISIBLE (-6048 3400);
FORCEADD TAP..1
R 2
(-6050 3350);
FORCEPROP 3 LASTPIN (-6000 3350) SIG_NAME M_G_CPU1_SB_CA<3>
J 0
(-5990 3360);
DISPLAY 0.659574 (-5990 3360);
PAINT MONO (-5990 3360);
DISPLAY INVISIBLE (-5990 3360);
FORCEPROP 1 LASTPIN (-6000 3350) BN 3
J 2
(-5988 3358);
DISPLAY 0.489362 (-5988 3358);
PAINT GREEN (-5988 3358);
FORCEPROP 2 LAST CDS_LIB mstr_standard
J 0
(-6050 3350);
DISPLAY 0.723404 (-6050 3350);
PAINT MONO (-6050 3350);
DISPLAY INVISIBLE (-6050 3350);
FORCEPROP 1 LAST BODY_TYPE PLUMBING
J 2
(-6050 3400);
DISPLAY 0.872340 (-6050 3400);
PAINT GREEN (-6050 3400);
DISPLAY INVISIBLE (-6050 3400);
FORCEPROP 1 LAST HDL_TAP TRUE
J 2
(-6375 3225);
DISPLAY 0.872340 (-6375 3225);
DISPLAY INVISIBLE (-6375 3225);
FORCEPROP 1 LAST PATH I306
J 2
(-6048 3350);
DISPLAY 0.872340 (-6048 3350);
PAINT GREEN (-6048 3350);
DISPLAY INVISIBLE (-6048 3350);
FORCEADD TAP..1
R 2
(-6050 3300);
FORCEPROP 3 LASTPIN (-6000 3300) SIG_NAME M_G_CPU1_SB_CA<4>
J 0
(-5990 3310);
DISPLAY 0.659574 (-5990 3310);
PAINT MONO (-5990 3310);
DISPLAY INVISIBLE (-5990 3310);
FORCEPROP 1 LASTPIN (-6000 3300) BN 4
J 2
(-5988 3308);
DISPLAY 0.489362 (-5988 3308);
PAINT GREEN (-5988 3308);
FORCEPROP 2 LAST CDS_LIB mstr_standard
J 0
(-6050 3300);
DISPLAY 0.723404 (-6050 3300);
PAINT MONO (-6050 3300);
DISPLAY INVISIBLE (-6050 3300);
FORCEPROP 1 LAST BODY_TYPE PLUMBING
J 2
(-6050 3350);
DISPLAY 0.872340 (-6050 3350);
PAINT GREEN (-6050 3350);
DISPLAY INVISIBLE (-6050 3350);
FORCEPROP 1 LAST HDL_TAP TRUE
J 2
(-6375 3175);
DISPLAY 0.872340 (-6375 3175);
DISPLAY INVISIBLE (-6375 3175);
FORCEPROP 1 LAST PATH I307
J 2
(-6048 3300);
DISPLAY 0.872340 (-6048 3300);
PAINT GREEN (-6048 3300);
DISPLAY INVISIBLE (-6048 3300);
FORCEADD TAP..1
R 2
(-6050 3250);
FORCEPROP 3 LASTPIN (-6000 3250) SIG_NAME M_G_CPU1_SB_CA<5>
J 0
(-5990 3260);
DISPLAY 0.659574 (-5990 3260);
PAINT MONO (-5990 3260);
DISPLAY INVISIBLE (-5990 3260);
FORCEPROP 1 LASTPIN (-6000 3250) BN 5
J 2
(-5988 3258);
DISPLAY 0.489362 (-5988 3258);
PAINT GREEN (-5988 3258);
FORCEPROP 2 LAST CDS_LIB mstr_standard
J 0
(-6050 3250);
DISPLAY 0.723404 (-6050 3250);
PAINT MONO (-6050 3250);
DISPLAY INVISIBLE (-6050 3250);
FORCEPROP 1 LAST BODY_TYPE PLUMBING
J 2
(-6050 3300);
DISPLAY 0.872340 (-6050 3300);
PAINT GREEN (-6050 3300);
DISPLAY INVISIBLE (-6050 3300);
FORCEPROP 1 LAST HDL_TAP TRUE
J 2
(-6375 3125);
DISPLAY 0.872340 (-6375 3125);
DISPLAY INVISIBLE (-6375 3125);
FORCEPROP 1 LAST PATH I308
J 2
(-6048 3250);
DISPLAY 0.872340 (-6048 3250);
PAINT GREEN (-6048 3250);
DISPLAY INVISIBLE (-6048 3250);
FORCEADD TAP..1
R 2
(-6050 3200);
FORCEPROP 3 LASTPIN (-6000 3200) SIG_NAME M_G_CPU1_SB_CA<6>
J 0
(-5990 3210);
DISPLAY 0.659574 (-5990 3210);
PAINT MONO (-5990 3210);
DISPLAY INVISIBLE (-5990 3210);
FORCEPROP 1 LASTPIN (-6000 3200) BN 6
J 2
(-5988 3208);
DISPLAY 0.489362 (-5988 3208);
PAINT GREEN (-5988 3208);
FORCEPROP 2 LAST CDS_LIB mstr_standard
J 0
(-6050 3200);
DISPLAY 0.723404 (-6050 3200);
PAINT MONO (-6050 3200);
DISPLAY INVISIBLE (-6050 3200);
FORCEPROP 1 LAST BODY_TYPE PLUMBING
J 2
(-6050 3250);
DISPLAY 0.872340 (-6050 3250);
PAINT GREEN (-6050 3250);
DISPLAY INVISIBLE (-6050 3250);
FORCEPROP 1 LAST HDL_TAP TRUE
J 2
(-6375 3075);
DISPLAY 0.872340 (-6375 3075);
DISPLAY INVISIBLE (-6375 3075);
FORCEPROP 1 LAST PATH I309
J 2
(-6048 3200);
DISPLAY 0.872340 (-6048 3200);
PAINT GREEN (-6048 3200);
DISPLAY INVISIBLE (-6048 3200);
FORCEADD OFFPAGE..2
R 2
(-6650 3925);
FORCEPROP 2 LAST $XR0 104 
J 0
(-6905 3925);
DISPLAY 0.638298 (-6905 3925);
PAINT MONO (-6905 3925);
FORCEPROP 2 LAST CDS_LIB standard
J 0
(-6650 3925);
DISPLAY INVISIBLE (-6650 3925);
FORCEPROP 1 LAST OFFPAGE TRUE
J 2
(-6975 3800);
DISPLAY 0.872340 (-6975 3800);
PAINT GREEN (-6975 3800);
DISPLAY INVISIBLE (-6975 3800);
FORCEPROP 1 LAST COMMENT_BODY TRUE
J 2
(-6605 3830);
DISPLAY 0.872340 (-6605 3830);
PAINT GREEN (-6605 3830);
DISPLAY INVISIBLE (-6605 3830);
FORCEPROP 2 LAST PATH I310
J 0
(-6900 3975);
DISPLAY 1.021277 (-6900 3975);
DISPLAY INVISIBLE (-6900 3975);
FORCEADD OFFPAGE..2
R 2
(-6650 3525);
FORCEPROP 2 LAST $XR0 104 
J 0
(-6905 3525);
DISPLAY 0.638298 (-6905 3525);
PAINT MONO (-6905 3525);
FORCEPROP 2 LAST CDS_LIB standard
J 0
(-6650 3525);
DISPLAY INVISIBLE (-6650 3525);
FORCEPROP 1 LAST OFFPAGE TRUE
J 2
(-6975 3400);
DISPLAY 0.872340 (-6975 3400);
PAINT GREEN (-6975 3400);
DISPLAY INVISIBLE (-6975 3400);
FORCEPROP 1 LAST COMMENT_BODY TRUE
J 2
(-6605 3430);
DISPLAY 0.872340 (-6605 3430);
PAINT GREEN (-6605 3430);
DISPLAY INVISIBLE (-6605 3430);
FORCEPROP 2 LAST PATH I311
J 0
(-6900 3575);
DISPLAY 1.021277 (-6900 3575);
DISPLAY INVISIBLE (-6900 3575);
FORCEADD OFFPAGE..2
R 2
(-6650 3000);
FORCEPROP 2 LAST $XR0 104 
J 0
(-6905 3000);
DISPLAY 0.638298 (-6905 3000);
PAINT MONO (-6905 3000);
FORCEPROP 2 LAST CDS_LIB standard
J 0
(-6650 3000);
DISPLAY INVISIBLE (-6650 3000);
FORCEPROP 1 LAST OFFPAGE TRUE
J 2
(-6975 2875);
DISPLAY 0.872340 (-6975 2875);
PAINT GREEN (-6975 2875);
DISPLAY INVISIBLE (-6975 2875);
FORCEPROP 1 LAST COMMENT_BODY TRUE
J 2
(-6605 2905);
DISPLAY 0.872340 (-6605 2905);
PAINT GREEN (-6605 2905);
DISPLAY INVISIBLE (-6605 2905);
FORCEPROP 2 LAST PATH I312
J 0
(-6900 3050);
DISPLAY 1.021277 (-6900 3050);
DISPLAY INVISIBLE (-6900 3050);
FORCEADD OFFPAGE..2
R 2
(-6650 3050);
FORCEPROP 2 LAST $XR0 104 
J 0
(-6905 3050);
DISPLAY 0.638298 (-6905 3050);
PAINT MONO (-6905 3050);
FORCEPROP 2 LAST CDS_LIB standard
J 0
(-6650 3050);
DISPLAY INVISIBLE (-6650 3050);
FORCEPROP 1 LAST OFFPAGE TRUE
J 2
(-6975 2925);
DISPLAY 0.872340 (-6975 2925);
PAINT GREEN (-6975 2925);
DISPLAY INVISIBLE (-6975 2925);
FORCEPROP 1 LAST COMMENT_BODY TRUE
J 2
(-6605 2955);
DISPLAY 0.872340 (-6605 2955);
PAINT GREEN (-6605 2955);
DISPLAY INVISIBLE (-6605 2955);
FORCEPROP 2 LAST PATH I313
J 0
(-6900 3100);
DISPLAY 1.021277 (-6900 3100);
DISPLAY INVISIBLE (-6900 3100);
FORCEADD OFFPAGE..2
R 2
(-6650 2900);
FORCEPROP 2 LAST $XR0 104 
J 0
(-6905 2900);
DISPLAY 0.638298 (-6905 2900);
PAINT MONO (-6905 2900);
FORCEPROP 2 LAST CDS_LIB standard
J 0
(-6650 2900);
DISPLAY INVISIBLE (-6650 2900);
FORCEPROP 1 LAST OFFPAGE TRUE
J 2
(-6975 2775);
DISPLAY 0.872340 (-6975 2775);
PAINT GREEN (-6975 2775);
DISPLAY INVISIBLE (-6975 2775);
FORCEPROP 1 LAST COMMENT_BODY TRUE
J 2
(-6605 2805);
DISPLAY 0.872340 (-6605 2805);
PAINT GREEN (-6605 2805);
DISPLAY INVISIBLE (-6605 2805);
FORCEPROP 2 LAST PATH I314
J 0
(-6900 2950);
DISPLAY 1.021277 (-6900 2950);
DISPLAY INVISIBLE (-6900 2950);
FORCEADD OFFPAGE..2
R 2
(-6650 2850);
FORCEPROP 2 LAST $XR0 104 
J 0
(-6905 2850);
DISPLAY 0.638298 (-6905 2850);
PAINT MONO (-6905 2850);
FORCEPROP 2 LAST CDS_LIB standard
J 0
(-6650 2850);
DISPLAY INVISIBLE (-6650 2850);
FORCEPROP 1 LAST OFFPAGE TRUE
J 2
(-6975 2725);
DISPLAY 0.872340 (-6975 2725);
PAINT GREEN (-6975 2725);
DISPLAY INVISIBLE (-6975 2725);
FORCEPROP 1 LAST COMMENT_BODY TRUE
J 2
(-6605 2755);
DISPLAY 0.872340 (-6605 2755);
PAINT GREEN (-6605 2755);
DISPLAY INVISIBLE (-6605 2755);
FORCEPROP 2 LAST PATH I315
J 0
(-6900 2900);
DISPLAY 1.021277 (-6900 2900);
DISPLAY INVISIBLE (-6900 2900);
FORCEADD OFFPAGE..5
(-6650 2650);
FORCEPROP 2 LAST $XR0 104 
J 0
(-6905 2650);
DISPLAY 0.638298 (-6905 2650);
PAINT MONO (-6905 2650);
FORCEPROP 2 LAST CDS_LIB mstr_standard
J 0
(-6650 2650);
DISPLAY INVISIBLE (-6650 2650);
FORCEPROP 1 LAST OFFPAGE TRUE
J 0
(-6325 2525);
DISPLAY 0.872340 (-6325 2525);
PAINT GREEN (-6325 2525);
DISPLAY INVISIBLE (-6325 2525);
FORCEPROP 1 LAST COMMENT_BODY TRUE
J 0
(-6550 2575);
DISPLAY 0.872340 (-6550 2575);
PAINT GREEN (-6550 2575);
DISPLAY INVISIBLE (-6550 2575);
FORCEPROP 2 LAST PATH I316
J 0
(-6900 2700);
DISPLAY 1.021277 (-6900 2700);
DISPLAY INVISIBLE (-6900 2700);
FORCEADD OFFPAGE..1
(-6650 2750);
FORCEPROP 2 LAST $XR0 104 
J 0
(-6902 2750);
DISPLAY 0.638298 (-6902 2750);
PAINT MONO (-6902 2750);
FORCEPROP 2 LAST CDS_LIB standard
J 0
(-6650 2750);
DISPLAY INVISIBLE (-6650 2750);
FORCEPROP 1 LAST OFFPAGE TRUE
J 0
(-6325 2625);
DISPLAY 0.872340 (-6325 2625);
PAINT GREEN (-6325 2625);
DISPLAY INVISIBLE (-6325 2625);
FORCEPROP 1 LAST COMMENT_BODY TRUE
J 0
(-6525 2650);
DISPLAY 0.872340 (-6525 2650);
PAINT GREEN (-6525 2650);
DISPLAY INVISIBLE (-6525 2650);
FORCEPROP 2 LAST PATH I317
J 0
(-6925 2800);
DISPLAY 1.021277 (-6925 2800);
DISPLAY INVISIBLE (-6925 2800);
FORCEADD OFFPAGE..2
R 2
(-6650 2550);
FORCEPROP 2 LAST $XR0 104 
J 0
(-6905 2550);
DISPLAY 0.638298 (-6905 2550);
PAINT MONO (-6905 2550);
FORCEPROP 2 LAST CDS_LIB standard
J 0
(-6650 2550);
DISPLAY INVISIBLE (-6650 2550);
FORCEPROP 1 LAST OFFPAGE TRUE
J 2
(-6975 2425);
DISPLAY 0.872340 (-6975 2425);
PAINT GREEN (-6975 2425);
DISPLAY INVISIBLE (-6975 2425);
FORCEPROP 1 LAST COMMENT_BODY TRUE
J 2
(-6605 2455);
DISPLAY 0.872340 (-6605 2455);
PAINT GREEN (-6605 2455);
DISPLAY INVISIBLE (-6605 2455);
FORCEPROP 2 LAST PATH I318
J 0
(-6900 2600);
DISPLAY 1.021277 (-6900 2600);
DISPLAY INVISIBLE (-6900 2600);
FORCEADD OFFPAGE..2
R 2
(-6650 2500);
FORCEPROP 2 LAST $XR0 104 
J 0
(-6905 2500);
DISPLAY 0.638298 (-6905 2500);
PAINT MONO (-6905 2500);
FORCEPROP 2 LAST CDS_LIB standard
J 0
(-6650 2500);
DISPLAY INVISIBLE (-6650 2500);
FORCEPROP 1 LAST OFFPAGE TRUE
J 2
(-6975 2375);
DISPLAY 0.872340 (-6975 2375);
PAINT GREEN (-6975 2375);
DISPLAY INVISIBLE (-6975 2375);
FORCEPROP 1 LAST COMMENT_BODY TRUE
J 2
(-6605 2405);
DISPLAY 0.872340 (-6605 2405);
PAINT GREEN (-6605 2405);
DISPLAY INVISIBLE (-6605 2405);
FORCEPROP 2 LAST PATH I319
J 0
(-6900 2550);
DISPLAY 1.021277 (-6900 2550);
DISPLAY INVISIBLE (-6900 2550);
FORCEADD OFFPAGE..1
(-6650 2400);
FORCEPROP 2 LAST $XR0 104 
J 0
(-6902 2400);
DISPLAY 0.638298 (-6902 2400);
PAINT MONO (-6902 2400);
FORCEPROP 2 LAST CDS_LIB standard
J 0
(-6650 2400);
DISPLAY INVISIBLE (-6650 2400);
FORCEPROP 1 LAST OFFPAGE TRUE
J 0
(-6325 2275);
DISPLAY 0.872340 (-6325 2275);
PAINT GREEN (-6325 2275);
DISPLAY INVISIBLE (-6325 2275);
FORCEPROP 1 LAST COMMENT_BODY TRUE
J 0
(-6525 2300);
DISPLAY 0.872340 (-6525 2300);
PAINT GREEN (-6525 2300);
DISPLAY INVISIBLE (-6525 2300);
FORCEPROP 2 LAST PATH I320
J 0
(-6925 2450);
DISPLAY 1.021277 (-6925 2450);
DISPLAY INVISIBLE (-6925 2450);
FORCEADD OFFPAGE..5
(-6650 2300);
FORCEPROP 2 LAST $XR0 104 
J 0
(-6905 2300);
DISPLAY 0.638298 (-6905 2300);
PAINT MONO (-6905 2300);
FORCEPROP 2 LAST CDS_LIB standard
J 0
(-6650 2300);
DISPLAY INVISIBLE (-6650 2300);
FORCEPROP 1 LAST OFFPAGE TRUE
J 0
(-6325 2175);
DISPLAY 0.872340 (-6325 2175);
PAINT GREEN (-6325 2175);
DISPLAY INVISIBLE (-6325 2175);
FORCEPROP 1 LAST COMMENT_BODY TRUE
J 0
(-6550 2225);
DISPLAY 0.872340 (-6550 2225);
PAINT GREEN (-6550 2225);
DISPLAY INVISIBLE (-6550 2225);
FORCEPROP 2 LAST PATH I321
J 0
(-6900 2350);
DISPLAY 1.021277 (-6900 2350);
DISPLAY INVISIBLE (-6900 2350);
FORCEADD Q_RES..1
(-6725 2200);
FORCEPROP 1 LAST LOCATION R506
J 0
(-7050 2200);
DISPLAY 0.489362 (-7050 2200);
PAINT SKYBLUE (-7050 2200);
FORCEPROP 0 LAST $SEC 1
J 0
(-6900 2250);
DISPLAY 0.680851 (-6900 2250);
PAINT MONO (-6900 2250);
DISPLAY INVISIBLE (-6900 2250);
FORCEPROP 0 LAST CDS_SEC 1
J 0
(-6900 2250);
DISPLAY 1.021277 (-6900 2250);
DISPLAY INVISIBLE (-6900 2250);
FORCEPROP 1 LASTPIN (-6825 2200) $PN 1
J 0
(-6813 2212);
DISPLAY 0.489362 (-6813 2212);
PAINT MONO (-6813 2212);
FORCEPROP 1 LASTPIN (-6625 2200) $PN 2
J 0
(-6663 2212);
DISPLAY 0.489362 (-6663 2212);
PAINT MONO (-6663 2212);
FORCEPROP 1 LAST PACK_TYPE 0402LF
J 0
(-7050 2175);
DISPLAY 0.489362 (-7050 2175);
PAINT SKYBLUE (-7050 2175);
FORCEPROP 1 LAST TOLERANCE 1%
J 0
(-6450 2200);
DISPLAY 0.489362 (-6450 2200);
PAINT SKYBLUE (-6450 2200);
FORCEPROP 1 LAST VALUE 15
J 2
(-6400 2200);
DISPLAY 0.489362 (-6400 2200);
PAINT SKYBLUE (-6400 2200);
FORCEPROP 1 LAST MATERIAL CHIP
J 0
(-6850 2325);
DISPLAY 0.638298 (-6850 2325);
PAINT SKYBLUE (-6850 2325);
DISPLAY INVISIBLE (-6850 2325);
FORCEPROP 1 LAST WATTAGE 1/16W
J 2
(-6500 2325);
DISPLAY 0.638298 (-6500 2325);
PAINT SKYBLUE (-6500 2325);
DISPLAY INVISIBLE (-6500 2325);
FORCEPROP 2 LAST CDS_LIB pure_quanta
J 0
(-6725 2200);
DISPLAY INVISIBLE (-6725 2200);
FORCEPROP 1 LAST PATH I322
J 0
(-6775 2350);
DISPLAY 0.978723 (-6775 2350);
PAINT WHITE (-6775 2350);
DISPLAY INVISIBLE (-6775 2350);
FORCEPROP 1 LAST PART_NUMBER CS01502FB03
J 0
(-6600 2175);
DISPLAY 0.489362 (-6600 2175);
PAINT SKYBLUE (-6600 2175);
DISPLAY INVISIBLE (-6600 2175);
FORCEADD OFFPAGE..5
(-6650 2100);
FORCEPROP 2 LAST $XR0 104 
J 0
(-6905 2100);
DISPLAY 0.638298 (-6905 2100);
PAINT MONO (-6905 2100);
FORCEPROP 2 LAST CDS_LIB standard
J 0
(-6650 2100);
DISPLAY INVISIBLE (-6650 2100);
FORCEPROP 1 LAST OFFPAGE TRUE
J 0
(-6325 1975);
DISPLAY 0.872340 (-6325 1975);
PAINT GREEN (-6325 1975);
DISPLAY INVISIBLE (-6325 1975);
FORCEPROP 1 LAST COMMENT_BODY TRUE
J 0
(-6550 2025);
DISPLAY 0.872340 (-6550 2025);
PAINT GREEN (-6550 2025);
DISPLAY INVISIBLE (-6550 2025);
FORCEPROP 2 LAST PATH I323
J 0
(-6900 2150);
DISPLAY 1.021277 (-6900 2150);
DISPLAY INVISIBLE (-6900 2150);
FORCEADD OFFPAGE..1
(-7600 2200);
FORCEPROP 2 LAST $XR0 104 
J 0
(-7852 2200);
DISPLAY 0.638298 (-7852 2200);
PAINT MONO (-7852 2200);
FORCEPROP 2 LAST CDS_LIB mstr_standard
J 0
(-7600 2200);
DISPLAY INVISIBLE (-7600 2200);
FORCEPROP 1 LAST OFFPAGE TRUE
J 0
(-7275 2075);
DISPLAY 0.872340 (-7275 2075);
PAINT GREEN (-7275 2075);
DISPLAY INVISIBLE (-7275 2075);
FORCEPROP 1 LAST COMMENT_BODY TRUE
J 0
(-7475 2100);
DISPLAY 0.872340 (-7475 2100);
PAINT GREEN (-7475 2100);
DISPLAY INVISIBLE (-7475 2100);
FORCEPROP 2 LAST PATH I324
J 0
(-7850 2250);
DISPLAY 1.021277 (-7850 2250);
DISPLAY INVISIBLE (-7850 2250);
FORCEADD CAD_NOTE..1
(-7875 2475);
FORCEPROP 0 LAST L1 R1964 PLACE CLOSE TO CPU < 25MM
J 0
(-8025 2350);
DISPLAY 0.617021 (-8025 2350);
PAINT WHITE (-8025 2350);
FORCEPROP 2 LAST CDS_LIB pure_quanta_power
J 0
(-7875 2475);
DISPLAY INVISIBLE (-7875 2475);
FORCEPROP 1 LAST COMMENT_BODY TRUE
J 0
(-7850 2575);
DISPLAY 0.574468 (-7850 2575);
PAINT WHITE (-7850 2575);
DISPLAY INVISIBLE (-7850 2575);
FORCEADD QUANTA_TITLE_BLOCK_C..1
(-100 100);
FORCEPROP 0 LAST CDS_CON_LAST_MODIFIED Thu Sep 14 16:11:57 2023
J 0
(-1985 115);
DISPLAY INVISIBLE (-1985 115);
FORCEPROP 1 LAST CUSTOM_TXT_CDS <CON_LAST_MODIFIED>
J 0
(-1985 115);
DISPLAY 0.978723 (-1985 115);
FORCEPROP 2 LAST CUSTOM_TXT_CDS <XR_PAGE_TITLE>
J 0
(-7990 5350);
DISPLAY 0.638298 (-7990 5350);
PAINT PINK (-7990 5350);
DISPLAY INVISIBLE (-7990 5350);
FORCEPROP 1 LAST CUSTOM_TXT_CDS <NAME_2>
J 0
(-3275 150);
FORCEPROP 1 LAST CUSTOM_TXT_CDS <NAME_1>
J 0
(-3275 275);
FORCEPROP 1 LAST CUSTOM_TXT_CDS <Q_NUMBER>
J 0
(-1503 203);
DISPLAY 1.212766 (-1503 203);
FORCEPROP 1 LAST CUSTOM_TXT_CDS <Q_PROJ>
J 0
(-2482 202);
DISPLAY 1.212766 (-2482 202);
FORCEPROP 1 LAST CUSTOM_TXT_CDS <Q_REV>
J 0
(-284 203);
DISPLAY 1.212766 (-284 203);
FORCEPROP 1 LAST CUSTOM_TXT_CDS <CON_PAGE_NUM> OF <CON_TOTAL_PAGES>
J 0
(-546 118);
DISPLAY 0.978723 (-546 118);
FORCEPROP 1 LAST Q_TITLE CPU1 DDR CHG
J 0
(-9375 150);
DISPLAY 2.446809 (-9375 150);
PAINT GREEN (-9375 150);
FORCEPROP 2 LAST CDS_LIB pure_quanta
J 0
(-100 100);
DISPLAY INVISIBLE (-100 100);
FORCEPROP 1 LAST CDS_LMAN_SYM_OUTLINE -9475,6775,100,-125
J 0
(-100 100);
DISPLAY 0.468085 (-100 100);
PAINT GREEN (-100 100);
DISPLAY INVISIBLE (-100 100);
FORCEPROP 2 LAST PAGE_BORDER TRUE
J 0
(-7990 5350);
DISPLAY 0.638298 (-7990 5350);
PAINT PINK (-7990 5350);
DISPLAY INVISIBLE (-7990 5350);
FORCEPROP 2 LAST CDS_XR_PAGE_TITLE CR-43 : @T6G_MB_LIB.T6G(SCH_1):PAGE43
J 0
(-7990 5350);
DISPLAY 0.638298 (-7990 5350);
PAINT PINK (-7990 5350);
DISPLAY INVISIBLE (-7990 5350);
FORCEPROP 1 LAST Q_DEPT BU9
J 1
(-3863 149);
DISPLAY 1.957447 (-3863 149);
PAINT GREEN (-3863 149);
DISPLAY INVISIBLE (-3863 149);
FORCEPROP 1 LAST COMMENT_BODY TRUE
J 0
(-88 87);
DISPLAY 0.978723 (-88 87);
PAINT GREEN (-88 87);
DISPLAY INVISIBLE (-88 87);
WIRE 17 -1 (-3375 5525)(-3375 5475);
WIRE 17 -1 (-3375 5575)(-3375 5525);
WIRE 17 -1 (-3375 5475)(-3375 5425);
WIRE 17 -1 (-3375 5425)(-3375 5375);
WIRE 17 -1 (-3375 5625)(-3375 5575);
WIRE 17 -1 (-3375 5725)(-3375 5625);
WIRE 17 -1 (-3375 5375)(-3375 5325);
WIRE 17 -1 (-3375 5325)(-3375 5275);
WIRE 17 -1 (-3375 5775)(-3375 5725);
WIRE 17 -1 (-3375 5825)(-3375 5775);
WIRE 17 -1 (-3375 5175)(-3375 5275);
WIRE 17 -1 (-3375 5125)(-3375 5175);
WIRE 17 -1 (-3375 5875)(-3375 5825);
WIRE 17 -1 (-3375 5925)(-3375 5875);
WIRE 17 -1 (-3375 5075)(-3375 5125);
WIRE 17 -1 (-3375 5025)(-3375 5075);
WIRE 17 -1 (-3375 5975)(-3375 5925);
WIRE 17 -1 (-3375 6025)(-3375 5975);
WIRE 17 -1 (-3375 5025)(-3375 4975);
WIRE 17 -1 (-3375 4975)(-3375 4925);
WIRE 17 -1 (-3375 6075)(-3375 6025);
WIRE 17 -1 (-3375 6075)(-2750 6075);
FORCEPROP 2 LAST SIG_NAME M_G_CPU1_SA_DQ<31:0>
J 2
(-2810 6085);
DISPLAY 0.489362 (-2810 6085);
WIRE 17 -1 (-3375 4925)(-3375 4875);
WIRE 17 -1 (-3375 4875)(-3375 4825);
WIRE 17 -1 (-3375 4825)(-3375 4725);
WIRE 17 -1 (-3375 4725)(-3375 4675);
WIRE 17 -1 (-3375 4675)(-3375 4625);
WIRE 17 -1 (-3375 4625)(-3375 4575);
WIRE 17 -1 (-3375 4525)(-3375 4575);
WIRE 17 -1 (-3375 4475)(-3375 4525);
WIRE 17 -1 (-3375 4425)(-3375 4475);
WIRE 17 -1 (-3375 4375)(-3375 4425);
WIRE 17 -1 (-3375 4275)(-3375 4225);
WIRE 17 -1 (-3375 4275)(-2750 4275);
FORCEPROP 2 LAST SIG_NAME M_G_CPU1_SB_DQ<31:0>
J 2
(-2810 4285);
DISPLAY 0.489362 (-2810 4285);
WIRE 17 -1 (-3375 4225)(-3375 4175);
WIRE 17 -1 (-3375 4175)(-3375 4125);
WIRE 17 -1 (-3375 4125)(-3375 4075);
WIRE 17 -1 (-3375 4075)(-3375 4025);
WIRE 17 -1 (-3375 4025)(-3375 3975);
WIRE 17 -1 (-3375 3975)(-3375 3925);
WIRE 17 -1 (-3375 3925)(-3375 3825);
WIRE 17 -1 (-3375 3225)(-3375 3175);
WIRE 17 -1 (-3375 3225)(-3375 3275);
WIRE 17 -1 (-3375 3175)(-3375 3125);
WIRE 17 -1 (-3375 3125)(-3375 3075);
WIRE 17 -1 (-3375 3275)(-3375 3325);
WIRE 17 -1 (-3375 3325)(-3375 3375);
WIRE 17 -1 (-3375 3075)(-3375 3025);
WIRE 17 -1 (-3375 3025)(-3375 2925);
WIRE 17 -1 (-3375 3375)(-3375 3475);
WIRE 17 -1 (-3375 3525)(-3375 3475);
WIRE 17 -1 (-3375 2925)(-3375 2875);
WIRE 17 -1 (-3375 2875)(-3375 2825);
WIRE 17 -1 (-3375 3575)(-3375 3525);
WIRE 17 -1 (-3375 3625)(-3375 3575);
WIRE 17 -1 (-3375 2825)(-3375 2775);
WIRE 17 -1 (-3375 2725)(-3375 2775);
WIRE 17 -1 (-3375 3675)(-3375 3625);
WIRE 17 -1 (-3375 3725)(-3375 3675);
WIRE 17 -1 (-3375 2675)(-3375 2725);
WIRE 17 -1 (-3375 2625)(-3375 2675);
WIRE 17 -1 (-3375 3775)(-3375 3725);
WIRE 17 -1 (-3375 3825)(-3375 3775);
WIRE 17 -1 (-3375 2575)(-3375 2625);
WIRE 17 -1 (-3375 2375)(-3375 2325);
WIRE 17 -1 (-3375 2375)(-3375 2425);
WIRE 17 -1 (-3375 2275)(-3375 2325);
WIRE 17 -1 (-3375 2225)(-3375 2275);
WIRE 17 -1 (-3375 2475)(-3375 2425);
WIRE 17 -1 (-3375 2475)(-3375 2500);
WIRE 17 -1 (-3375 2175)(-3375 2225);
WIRE 17 -1 (-3375 2125)(-3375 2175);
WIRE 17 -1 (-3375 2500)(-2875 2500);
FORCEPROP 2 LAST SIG_NAME M_G_CPU1_SA_CB<7:0>
J 2
(-2875 2510);
DISPLAY 0.489362 (-2875 2510);
WIRE 17 -1 (-3375 2025)(-3375 2050);
WIRE 17 -1 (-3375 2025)(-3375 1975);
WIRE 17 -1 (-3375 2050)(-2875 2050);
FORCEPROP 2 LAST SIG_NAME M_G_CPU1_SB_CB<7:0>
J 2
(-2875 2060);
DISPLAY 0.489362 (-2875 2060);
WIRE 17 -1 (-3375 1925)(-3375 1975);
WIRE 17 -1 (-3375 1925)(-3375 1875);
WIRE 17 -1 (-3375 1825)(-3375 1875);
WIRE 17 -1 (-3375 1775)(-3375 1825);
WIRE 17 -1 (-3375 1725)(-3375 1775);
WIRE 17 -1 (-3375 1675)(-3375 1725);
WIRE 17 -1 (-6100 6025)(-6100 5925);
FORCEPROP 2 LAST SIG_NAME M_G_CPU1_SA_DQS_DN<9:0>
J 2
(-6135 6035);
DISPLAY 0.489362 (-6135 6035);
WIRE 17 -1 (-6100 5925)(-6100 5825);
WIRE 17 -1 (-6100 5825)(-6100 5725);
WIRE 17 -1 (-6100 5725)(-6100 5625);
WIRE 17 -1 (-6100 5525)(-6100 5625);
WIRE 17 -1 (-6100 5425)(-6100 5525);
WIRE 17 -1 (-5900 6075)(-5900 5975);
WIRE 17 -1 (-5900 6075)(-6700 6075);
FORCEPROP 2 LAST SIG_NAME M_G_CPU1_SA_DQS_DP<9:0>
J 2
(-6135 6085);
DISPLAY 0.489362 (-6135 6085);
WIRE 17 -1 (-6100 5325)(-6100 5425);
WIRE 17 -1 (-6100 5325)(-6100 5225);
WIRE 17 -1 (-6100 5225)(-6100 5125);
WIRE 17 -1 (-5900 5975)(-5900 5875);
WIRE 17 -1 (-5900 5875)(-5900 5775);
WIRE 17 -1 (-5900 5775)(-5900 5675);
WIRE 17 -1 (-5900 5575)(-5900 5675);
WIRE 17 -1 (-5900 5475)(-5900 5575);
WIRE 17 -1 (-5900 5375)(-5900 5475);
WIRE 17 -1 (-5900 5375)(-5900 5275);
WIRE 17 -1 (-5900 5275)(-5900 5175);
WIRE 17 -1 (-5900 4525)(-5900 4625);
WIRE 17 -1 (-5900 4425)(-5900 4525);
WIRE 17 -1 (-5900 4725)(-5900 4625);
WIRE 17 -1 (-5900 4825)(-5900 4725);
WIRE 17 -1 (-5900 4325)(-5900 4425);
WIRE 17 -1 (-5900 4325)(-5900 4225);
WIRE 17 -1 (-5900 4925)(-5900 4825);
WIRE 17 -1 (-5900 5025)(-5900 4925);
WIRE 17 -1 (-5900 4225)(-5900 4125);
WIRE 17 -1 (-5900 5025)(-6700 5025);
FORCEPROP 2 LAST SIG_NAME M_G_CPU1_SB_DQS_DP<9:0>
J 2
(-6135 5035);
DISPLAY 0.489362 (-6135 5035);
WIRE 17 -1 (-6100 4975)(-6100 4875);
FORCEPROP 2 LAST SIG_NAME M_G_CPU1_SB_DQS_DN<9:0>
J 2
(-6135 4985);
DISPLAY 0.489362 (-6135 4985);
WIRE 17 -1 (-6100 4875)(-6100 4775);
WIRE 17 -1 (-6100 4775)(-6100 4675);
WIRE 17 -1 (-6100 4675)(-6100 4575);
WIRE 17 -1 (-6100 4475)(-6100 4575);
WIRE 17 -1 (-6100 4375)(-6100 4475);
WIRE 17 -1 (-6100 4275)(-6100 4375);
WIRE 17 -1 (-6100 4275)(-6100 4175);
WIRE 17 -1 (-6100 4175)(-6100 4075);
WIRE 17 -1 (-6100 3875)(-6100 3925);
WIRE 17 -1 (-6100 3825)(-6100 3875);
WIRE 17 -1 (-6100 3925)(-6600 3925);
FORCEPROP 2 LAST SIG_NAME M_G_CPU1_SA_CA<6:0>
J 0
(-6600 3935);
DISPLAY 0.489362 (-6600 3935);
WIRE 17 -1 (-6100 3475)(-6100 3525);
WIRE 17 -1 (-6100 3425)(-6100 3475);
WIRE 17 -1 (-6100 3525)(-6600 3525);
FORCEPROP 2 LAST SIG_NAME M_G_CPU1_SB_CA<6:0>
J 0
(-6600 3535);
DISPLAY 0.489362 (-6600 3535);
WIRE 17 -1 (-6100 3775)(-6100 3825);
WIRE 17 -1 (-6100 3375)(-6100 3425);
WIRE 17 -1 (-6100 3725)(-6100 3775);
WIRE 17 -1 (-6100 3675)(-6100 3725);
WIRE 17 -1 (-6100 3625)(-6100 3675);
WIRE 17 -1 (-6100 3325)(-6100 3375);
WIRE 17 -1 (-6100 3275)(-6100 3325);
WIRE 17 -1 (-6100 3225)(-6100 3275);
WIRE 17 -1 (-6100 6025)(-6700 6025);
WIRE 17 -1 (-6100 4975)(-6700 4975);
WIRE 16 -1 (-7550 2200)(-6825 2200);
FORCEPROP 2 LAST SIG_NAME M_G_CPU1_ALERT_N
J 0
(-7510 2210);
DISPLAY 0.489362 (-7510 2210);
WIRE 16 -1 (-6625 2200)(-5500 2200);
FORCEPROP 2 LAST SIG_NAME M_G_CPU1_ALERT_R_N
J 0
(-6335 2210);
DISPLAY 0.489362 (-6335 2210);
FORCEPROP 2 LASTPROP $XRERR UNIQUE?
J 0
(-6575 2210);
DISPLAY 0.638298 (-6575 2210);
PAINT MONO (-6575 2210);
DISPLAY INVISIBLE (-6575 2210);
WIRE 16 -1 (-6600 1250)(-5500 1250);
FORCEPROP 2 LAST SIG_NAME TP_M_G_CPU1_SA_TEST39G
J 0
(-6585 1260);
DISPLAY 0.489362 (-6585 1260);
FORCEPROP 2 LASTPROP $XRERR UNIQUE?
J 0
(-6840 1250);
DISPLAY 0.638298 (-6840 1250);
PAINT MONO (-6840 1250);
DISPLAY INVISIBLE (-6840 1250);
WIRE 16 -1 (-6600 3000)(-5500 3000);
FORCEPROP 2 LAST SIG_NAME M_G_CPU1_CLK_DN<0>
J 0
(-6600 3010);
DISPLAY 0.489362 (-6600 3010);
WIRE 16 -1 (-6600 3050)(-5500 3050);
FORCEPROP 2 LAST SIG_NAME M_G_CPU1_CLK_DP<0>
J 0
(-6600 3060);
DISPLAY 0.489362 (-6600 3060);
WIRE 16 -1 (-6600 2900)(-5500 2900);
FORCEPROP 2 LAST SIG_NAME M_G_CPU1_SA_CS_N<0>
J 0
(-6600 2910);
DISPLAY 0.489362 (-6600 2910);
WIRE 16 -1 (-6600 2850)(-5500 2850);
FORCEPROP 2 LAST SIG_NAME M_G_CPU1_SA_CS_N<1>
J 0
(-6600 2860);
DISPLAY 0.489362 (-6600 2860);
WIRE 16 -1 (-6600 2650)(-5500 2650);
FORCEPROP 2 LAST SIG_NAME M_G_CPU1_SA_PAR
J 0
(-6600 2660);
DISPLAY 0.489362 (-6600 2660);
WIRE 16 -1 (-6600 2750)(-5500 2750);
FORCEPROP 2 LAST SIG_NAME M_G_CPU1_SA_RSP<0>
J 0
(-6600 2760);
DISPLAY 0.489362 (-6600 2760);
WIRE 16 -1 (-6600 2550)(-5500 2550);
FORCEPROP 2 LAST SIG_NAME M_G_CPU1_SB_CS_N<0>
J 0
(-6600 2560);
DISPLAY 0.489362 (-6600 2560);
WIRE 16 -1 (-6600 2500)(-5500 2500);
FORCEPROP 2 LAST SIG_NAME M_G_CPU1_SB_CS_N<1>
J 0
(-6600 2510);
DISPLAY 0.489362 (-6600 2510);
WIRE 16 -1 (-6600 2400)(-5500 2400);
FORCEPROP 2 LAST SIG_NAME M_G_CPU1_SB_RSP<0>
J 0
(-6600 2410);
DISPLAY 0.489362 (-6600 2410);
WIRE 16 -1 (-6600 2300)(-5500 2300);
FORCEPROP 2 LAST SIG_NAME M_G_CPU1_SB_PAR
J 0
(-6600 2310);
DISPLAY 0.489362 (-6600 2310);
WIRE 16 -1 (-6600 2100)(-5500 2100);
FORCEPROP 2 LAST SIG_NAME M_G_CPU1_RESET_N
J 0
(-6600 2110);
DISPLAY 0.489362 (-6600 2110);
WIRE 16 -1 (-6000 3200)(-5500 3200);
WIRE 16 -1 (-6000 3600)(-5500 3600);
WIRE 16 -1 (-6000 3250)(-5500 3250);
WIRE 16 -1 (-6000 3650)(-5500 3650);
WIRE 16 -1 (-6000 3300)(-5500 3300);
WIRE 16 -1 (-6000 3700)(-5500 3700);
WIRE 16 -1 (-6000 3350)(-5500 3350);
WIRE 16 -1 (-6000 3750)(-5500 3750);
WIRE 16 -1 (-6000 3400)(-5500 3400);
WIRE 16 -1 (-6000 3800)(-5500 3800);
WIRE 16 -1 (-6000 3450)(-5500 3450);
WIRE 16 -1 (-6000 3850)(-5500 3850);
WIRE 16 -1 (-6000 3500)(-5500 3500);
WIRE 16 -1 (-6000 3900)(-5500 3900);
WIRE 16 -1 (-6000 4050)(-5500 4050);
WIRE 16 -1 (-5800 4100)(-5500 4100);
WIRE 16 -1 (-5800 4600)(-5500 4600);
WIRE 16 -1 (-6000 4150)(-5500 4150);
WIRE 16 -1 (-5800 4700)(-5500 4700);
WIRE 16 -1 (-6000 4250)(-5500 4250);
WIRE 16 -1 (-5800 4800)(-5500 4800);
WIRE 16 -1 (-6000 4350)(-5500 4350);
WIRE 16 -1 (-5800 4900)(-5500 4900);
WIRE 16 -1 (-6000 4450)(-5500 4450);
WIRE 16 -1 (-5800 5000)(-5500 5000);
WIRE 16 -1 (-6000 4550)(-5500 4550);
WIRE 16 -1 (-6000 5100)(-5500 5100);
WIRE 16 -1 (-6000 4650)(-5500 4650);
WIRE 16 -1 (-6000 4750)(-5500 4750);
WIRE 16 -1 (-6000 4850)(-5500 4850);
WIRE 16 -1 (-6000 4950)(-5500 4950);
WIRE 16 -1 (-5800 4200)(-5500 4200);
WIRE 16 -1 (-5800 4300)(-5500 4300);
WIRE 16 -1 (-5800 4400)(-5500 4400);
WIRE 16 -1 (-5800 4500)(-5500 4500);
WIRE 16 -1 (-5800 5150)(-5500 5150);
WIRE 16 -1 (-5800 5250)(-5500 5250);
WIRE 16 -1 (-5800 5350)(-5500 5350);
WIRE 16 -1 (-5800 5450)(-5500 5450);
WIRE 16 -1 (-5800 5550)(-5500 5550);
WIRE 16 -1 (-5800 5650)(-5500 5650);
WIRE 16 -1 (-6000 5200)(-5500 5200);
WIRE 16 -1 (-5800 5750)(-5500 5750);
WIRE 16 -1 (-6000 5300)(-5500 5300);
WIRE 16 -1 (-5800 5850)(-5500 5850);
WIRE 16 -1 (-6000 5400)(-5500 5400);
WIRE 16 -1 (-5800 5950)(-5500 5950);
WIRE 16 -1 (-6000 5500)(-5500 5500);
WIRE 16 -1 (-5800 6050)(-5500 6050);
WIRE 16 -1 (-6000 5600)(-5500 5600);
WIRE 16 -1 (-6000 5700)(-5500 5700);
WIRE 16 -1 (-6000 5800)(-5500 5800);
WIRE 16 -1 (-6000 5900)(-5500 5900);
WIRE 16 -1 (-6000 6000)(-5500 6000);
WIRE 16 -1 (-3900 1650)(-3475 1650);
WIRE 16 -1 (-3900 1700)(-3475 1700);
WIRE 16 -1 (-3900 1750)(-3475 1750);
WIRE 16 -1 (-3900 1800)(-3475 1800);
WIRE 16 -1 (-3900 1850)(-3475 1850);
WIRE 16 -1 (-3900 1900)(-3475 1900);
WIRE 16 -1 (-3900 1950)(-3475 1950);
WIRE 16 -1 (-3900 2000)(-3475 2000);
WIRE 16 -1 (-3900 2400)(-3475 2400);
WIRE 16 -1 (-3900 2450)(-3475 2450);
WIRE 16 -1 (-3900 2650)(-3475 2650);
WIRE 16 -1 (-3900 2700)(-3475 2700);
WIRE 16 -1 (-3900 2750)(-3475 2750);
WIRE 16 -1 (-3900 2800)(-3475 2800);
WIRE 16 -1 (-3900 2850)(-3475 2850);
WIRE 16 -1 (-3900 2900)(-3475 2900);
WIRE 16 -1 (-3900 3000)(-3475 3000);
WIRE 16 -1 (-3900 3050)(-3475 3050);
WIRE 16 -1 (-3900 2100)(-3475 2100);
WIRE 16 -1 (-3900 2150)(-3475 2150);
WIRE 16 -1 (-3900 2550)(-3475 2550);
WIRE 16 -1 (-3900 2200)(-3475 2200);
WIRE 16 -1 (-3900 2600)(-3475 2600);
WIRE 16 -1 (-3900 2250)(-3475 2250);
WIRE 16 -1 (-3900 2300)(-3475 2300);
WIRE 16 -1 (-3900 2350)(-3475 2350);
WIRE 16 -1 (-3900 3200)(-3475 3200);
WIRE 16 -1 (-3900 3250)(-3475 3250);
WIRE 16 -1 (-3900 3300)(-3475 3300);
WIRE 16 -1 (-3900 3350)(-3475 3350);
WIRE 16 -1 (-3900 3450)(-3475 3450);
WIRE 16 -1 (-3900 3500)(-3475 3500);
WIRE 16 -1 (-3900 3750)(-3475 3750);
WIRE 16 -1 (-3900 3550)(-3475 3550);
WIRE 16 -1 (-3900 3800)(-3475 3800);
WIRE 16 -1 (-3900 3600)(-3475 3600);
WIRE 16 -1 (-3900 3900)(-3475 3900);
WIRE 16 -1 (-3900 3650)(-3475 3650);
WIRE 16 -1 (-3900 3950)(-3475 3950);
WIRE 16 -1 (-3900 3700)(-3475 3700);
WIRE 16 -1 (-3900 3100)(-3475 3100);
WIRE 16 -1 (-3900 4000)(-3475 4000);
WIRE 16 -1 (-3900 3150)(-3475 3150);
WIRE 16 -1 (-3900 4050)(-3475 4050);
WIRE 16 -1 (-3900 4900)(-3475 4900);
WIRE 16 -1 (-3900 4250)(-3475 4250);
WIRE 16 -1 (-3900 4950)(-3475 4950);
WIRE 16 -1 (-3900 4350)(-3475 4350);
WIRE 16 -1 (-3900 4400)(-3475 4400);
WIRE 16 -1 (-3900 5000)(-3475 5000);
WIRE 16 -1 (-3900 5050)(-3475 5050);
WIRE 16 -1 (-3900 4450)(-3475 4450);
WIRE 16 -1 (-3900 5100)(-3475 5100);
WIRE 16 -1 (-3900 4500)(-3475 4500);
WIRE 16 -1 (-3900 4550)(-3475 4550);
WIRE 16 -1 (-3900 4600)(-3475 4600);
WIRE 16 -1 (-3900 4650)(-3475 4650);
WIRE 16 -1 (-3900 4700)(-3475 4700);
WIRE 16 -1 (-3900 4100)(-3475 4100);
WIRE 16 -1 (-3900 4800)(-3475 4800);
WIRE 16 -1 (-3900 4150)(-3475 4150);
WIRE 16 -1 (-3900 4850)(-3475 4850);
WIRE 16 -1 (-3900 4200)(-3475 4200);
WIRE 16 -1 (-3900 6050)(-3475 6050);
WIRE 16 -1 (-3900 5500)(-3475 5500);
WIRE 16 -1 (-3900 5550)(-3475 5550);
WIRE 16 -1 (-3900 5600)(-3475 5600);
WIRE 16 -1 (-3900 5700)(-3475 5700);
WIRE 16 -1 (-3900 5750)(-3475 5750);
WIRE 16 -1 (-3900 5150)(-3475 5150);
WIRE 16 -1 (-3900 5800)(-3475 5800);
WIRE 16 -1 (-3900 5250)(-3475 5250);
WIRE 16 -1 (-3900 5850)(-3475 5850);
WIRE 16 -1 (-3900 5300)(-3475 5300);
WIRE 16 -1 (-3900 5900)(-3475 5900);
WIRE 16 -1 (-3900 5350)(-3475 5350);
WIRE 16 -1 (-3900 5950)(-3475 5950);
WIRE 16 -1 (-3900 5400)(-3475 5400);
WIRE 16 -1 (-3900 6000)(-3475 6000);
WIRE 16 -1 (-3900 5450)(-3475 5450);
QUIT
